G04 ================== begin FILE IDENTIFICATION RECORD ==================*
G04 Layout Name:  D:/<user>/Wistron_project/16342-2/gbr/16342-2.brd*
G04 Film Name:    DP_REF_L6*
G04 File Format:  Gerber RS274X*
G04 File Origin:  Cadence Allegro 16.5-S056*
G04 Origin Date:  Mon Aug 07 11:25:06 2017*
G04 *
G04 Layer:  BOARD GEOMETRY/DP_REF_L6_TBL*
G04 Layer:  BOARD GEOMETRY/DP_REF_L6_L6*
G04 Layer:  BOARD GEOMETRY/PANEL_OUTLINE*
G04 *
G04 Offset:    (0.00 0.00)*
G04 Mirror:    No*
G04 Mode:      Positive*
G04 Rotation:  0*
G04 FullContactRelief:  No*
G04 UndefLineWidth:     6.00*
G04 ================== end FILE IDENTIFICATION RECORD ====================*
%FSLAX35Y35*MOIN*%
%IR0*IPPOS*OFA0.00000B0.00000*MIA0B0*SFA1.00000B1.00000*%
%ADD10C,.02*%
%ADD11C,.006*%
%ADD12C,.0055*%
G75*
%LPD*%
G75*
G54D10*
G01X975497Y625480D02*
X1762997D01*
G01X975497Y729430D02*
Y625480D01*
G01Y694780D02*
X1762997D01*
G01X975497Y660130D02*
X1762997D01*
G01X975497Y729430D02*
X1762997D01*
G01X1150497D02*
Y625480D01*
G01X1447997Y729430D02*
Y625480D01*
G01X1552997Y729430D02*
Y625480D01*
G01X1762997Y729430D02*
Y625480D01*
G54D11*
G01X6250Y-32800D02*
Y-50300D01*
G01X1228Y-32800D02*
X11272D01*
G01X20038Y-50300D02*
Y-32800D01*
G01Y-41258D02*
X21130Y-39800D01*
X22222Y-38925D01*
X23968Y-38634D01*
X25278Y-38925D01*
X26807Y-40092D01*
X27462Y-41842D01*
Y-50300D01*
G01X41250Y-38634D02*
Y-50300D01*
G01Y-33967D02*
X40813Y-33675D01*
Y-33092D01*
X41250Y-32800D01*
X41687Y-33092D01*
Y-33675D01*
X41250Y-33967D01*
G01X55475Y-48259D02*
X56567Y-49425D01*
X58095Y-50300D01*
X59405D01*
X60715Y-49717D01*
X61588Y-48842D01*
X62025Y-47676D01*
X61807Y-45925D01*
X60933Y-45050D01*
X57003Y-43300D01*
X56130Y-41258D01*
X56567Y-39800D01*
X57440Y-38925D01*
X58750Y-38634D01*
X60060Y-38925D01*
X61370Y-39800D01*
G01X90693Y-54675D02*
X92222Y-55842D01*
X93968Y-56133D01*
X95496Y-55842D01*
X96807Y-54384D01*
X97680Y-52342D01*
Y-38634D01*
G01Y-40967D02*
X96807Y-39800D01*
X95496Y-38925D01*
X93968Y-38634D01*
X92222Y-39217D01*
X91130Y-40383D01*
X90256Y-42425D01*
X89820Y-44467D01*
X90038Y-46217D01*
X90912Y-48259D01*
X92222Y-49717D01*
X93968Y-50300D01*
X95278Y-50008D01*
X96807Y-48842D01*
X97680Y-47676D01*
G01X107975Y-42425D02*
X114962D01*
X114307Y-40383D01*
X113215Y-39217D01*
X111687Y-38634D01*
X110158Y-38925D01*
X108848Y-39800D01*
X107975Y-41842D01*
X107538Y-43592D01*
Y-45342D01*
X107975Y-47092D01*
X109067Y-48842D01*
X110377Y-50008D01*
X111905Y-50300D01*
X113433Y-49717D01*
X114962Y-47967D01*
G01X125693Y-50300D02*
Y-38634D01*
G01Y-40967D02*
X126785Y-39800D01*
X127877Y-38925D01*
X129405Y-38634D01*
X130496Y-38925D01*
X131807Y-39800D01*
G01X142320Y-50300D02*
Y-32800D01*
G01Y-41550D02*
X143412Y-39800D01*
X144722Y-38925D01*
X146032Y-38634D01*
X147996Y-39217D01*
X149307Y-40383D01*
X150180Y-42425D01*
Y-44758D01*
X149743Y-47092D01*
X148870Y-48842D01*
X147342Y-50008D01*
X146032Y-50300D01*
X144722Y-50008D01*
X143412Y-49134D01*
X142320Y-47676D01*
G01X160475Y-42425D02*
X167462D01*
X166807Y-40383D01*
X165715Y-39217D01*
X164187Y-38634D01*
X162658Y-38925D01*
X161348Y-39800D01*
X160475Y-41842D01*
X160038Y-43592D01*
Y-45342D01*
X160475Y-47092D01*
X161567Y-48842D01*
X162877Y-50008D01*
X164405Y-50300D01*
X165933Y-49717D01*
X167462Y-47967D01*
G01X178193Y-50300D02*
Y-38634D01*
G01Y-40967D02*
X179285Y-39800D01*
X180377Y-38925D01*
X181905Y-38634D01*
X182996Y-38925D01*
X184307Y-39800D01*
G01X216250Y-38634D02*
Y-50300D01*
G01Y-33967D02*
X215813Y-33675D01*
Y-33092D01*
X216250Y-32800D01*
X216687Y-33092D01*
Y-33675D01*
X216250Y-33967D01*
G01X230475Y-48259D02*
X231567Y-49425D01*
X233095Y-50300D01*
X234405D01*
X235715Y-49717D01*
X236588Y-48842D01*
X237025Y-47676D01*
X236807Y-45925D01*
X235933Y-45050D01*
X232003Y-43300D01*
X231130Y-41258D01*
X231567Y-39800D01*
X232440Y-38925D01*
X233750Y-38634D01*
X235060Y-38925D01*
X236370Y-39800D01*
G01X265256Y-54675D02*
X266785Y-55842D01*
X268095Y-56133D01*
X269842Y-55550D01*
X271152Y-54092D01*
X271807Y-51466D01*
Y-38634D01*
G01Y-33967D02*
X271370Y-33675D01*
Y-33092D01*
X271807Y-32800D01*
X272243Y-33092D01*
Y-33675D01*
X271807Y-33967D01*
G01X282538Y-38634D02*
Y-46800D01*
X283412Y-48842D01*
X284722Y-50008D01*
X286250Y-50300D01*
X287778Y-50008D01*
X289088Y-48842D01*
X289962Y-46800D01*
G01Y-50300D02*
Y-38634D01*
G01X300475Y-48259D02*
X301567Y-49425D01*
X303095Y-50300D01*
X304405D01*
X305715Y-49717D01*
X306588Y-48842D01*
X307025Y-47676D01*
X306807Y-45925D01*
X305933Y-45050D01*
X302003Y-43300D01*
X301130Y-41258D01*
X301567Y-39800D01*
X302440Y-38925D01*
X303750Y-38634D01*
X305060Y-38925D01*
X306370Y-39800D01*
G01X321250Y-32800D02*
Y-50300D01*
G01X318193Y-38634D02*
X324307D01*
G01X354940Y-50300D02*
Y-35425D01*
X355377Y-33967D01*
X356250Y-33092D01*
X357560Y-32800D01*
X358870Y-33383D01*
X359525Y-34842D01*
G01X356905Y-39800D02*
X352538D01*
G01X373750Y-50300D02*
X372440Y-50008D01*
X371130Y-48842D01*
X370256Y-46800D01*
X369820Y-44467D01*
X370256Y-42133D01*
X371130Y-40092D01*
X372440Y-38925D01*
X373750Y-38634D01*
X375060Y-38925D01*
X376370Y-40092D01*
X377243Y-42133D01*
X377462Y-44467D01*
X377243Y-46800D01*
X376370Y-48842D01*
X375060Y-50008D01*
X373750Y-50300D01*
G01X388193D02*
Y-38634D01*
G01Y-40967D02*
X389285Y-39800D01*
X390377Y-38925D01*
X391905Y-38634D01*
X392996Y-38925D01*
X394307Y-39800D01*
G01X421665Y-55550D02*
X422975Y-56133D01*
X424722Y-55550D01*
X425813Y-54384D01*
X426687Y-52925D01*
X427996Y-48259D01*
X430835Y-38634D01*
G01X423848D02*
X427996Y-48259D01*
G01X443750Y-50300D02*
X442440Y-50008D01*
X441130Y-48842D01*
X440256Y-46800D01*
X439820Y-44467D01*
X440256Y-42133D01*
X441130Y-40092D01*
X442440Y-38925D01*
X443750Y-38634D01*
X445060Y-38925D01*
X446370Y-40092D01*
X447243Y-42133D01*
X447462Y-44467D01*
X447243Y-46800D01*
X446370Y-48842D01*
X445060Y-50008D01*
X443750Y-50300D01*
G01X457538Y-38634D02*
Y-46800D01*
X458412Y-48842D01*
X459722Y-50008D01*
X461250Y-50300D01*
X462778Y-50008D01*
X464088Y-48842D01*
X464962Y-46800D01*
G01Y-50300D02*
Y-38634D01*
G01X475693Y-50300D02*
Y-38634D01*
G01Y-40967D02*
X476785Y-39800D01*
X477877Y-38925D01*
X479405Y-38634D01*
X480496Y-38925D01*
X481807Y-39800D01*
G01X510693Y-50300D02*
Y-38634D01*
G01Y-40967D02*
X511785Y-39800D01*
X512877Y-38925D01*
X514405Y-38634D01*
X515496Y-38925D01*
X516807Y-39800D01*
G01X527975Y-42425D02*
X534962D01*
X534307Y-40383D01*
X533215Y-39217D01*
X531687Y-38634D01*
X530158Y-38925D01*
X528848Y-39800D01*
X527975Y-41842D01*
X527538Y-43592D01*
Y-45342D01*
X527975Y-47092D01*
X529067Y-48842D01*
X530377Y-50008D01*
X531905Y-50300D01*
X533433Y-49717D01*
X534962Y-47967D01*
G01X547440Y-50300D02*
Y-35425D01*
X547877Y-33967D01*
X548750Y-33092D01*
X550060Y-32800D01*
X551370Y-33383D01*
X552025Y-34842D01*
G01X549405Y-39800D02*
X545038D01*
G01X562975Y-42425D02*
X569962D01*
X569307Y-40383D01*
X568215Y-39217D01*
X566687Y-38634D01*
X565158Y-38925D01*
X563848Y-39800D01*
X562975Y-41842D01*
X562538Y-43592D01*
Y-45342D01*
X562975Y-47092D01*
X564067Y-48842D01*
X565377Y-50008D01*
X566905Y-50300D01*
X568433Y-49717D01*
X569962Y-47967D01*
G01X580693Y-50300D02*
Y-38634D01*
G01Y-40967D02*
X581785Y-39800D01*
X582877Y-38925D01*
X584405Y-38634D01*
X585496Y-38925D01*
X586807Y-39800D01*
G01X597975Y-42425D02*
X604962D01*
X604307Y-40383D01*
X603215Y-39217D01*
X601687Y-38634D01*
X600158Y-38925D01*
X598848Y-39800D01*
X597975Y-41842D01*
X597538Y-43592D01*
Y-45342D01*
X597975Y-47092D01*
X599067Y-48842D01*
X600377Y-50008D01*
X601905Y-50300D01*
X603433Y-49717D01*
X604962Y-47967D01*
G01X615038Y-50300D02*
Y-38634D01*
G01Y-41550D02*
X615912Y-40092D01*
X617222Y-38925D01*
X618968Y-38634D01*
X620496Y-38925D01*
X621807Y-40092D01*
X622462Y-42133D01*
Y-50300D01*
G01X639743Y-40092D02*
X638215Y-38925D01*
X636905Y-38634D01*
X635158Y-39217D01*
X633848Y-40383D01*
X632975Y-42425D01*
X632756Y-44467D01*
X632975Y-46509D01*
X633848Y-48259D01*
X635158Y-49717D01*
X636905Y-50300D01*
X638433Y-49717D01*
X639743Y-48550D01*
G01X650475Y-42425D02*
X657462D01*
X656807Y-40383D01*
X655715Y-39217D01*
X654187Y-38634D01*
X652658Y-38925D01*
X651348Y-39800D01*
X650475Y-41842D01*
X650038Y-43592D01*
Y-45342D01*
X650475Y-47092D01*
X651567Y-48842D01*
X652877Y-50008D01*
X654405Y-50300D01*
X655933Y-49717D01*
X657462Y-47967D01*
G01X688750Y-32800D02*
Y-50300D01*
G01X685693Y-38634D02*
X691807D01*
G01X706250Y-50300D02*
X704940Y-50008D01*
X703630Y-48842D01*
X702756Y-46800D01*
X702320Y-44467D01*
X702756Y-42133D01*
X703630Y-40092D01*
X704940Y-38925D01*
X706250Y-38634D01*
X707560Y-38925D01*
X708870Y-40092D01*
X709743Y-42133D01*
X709962Y-44467D01*
X709743Y-46800D01*
X708870Y-48842D01*
X707560Y-50008D01*
X706250Y-50300D01*
G01X739940D02*
Y-35425D01*
X740377Y-33967D01*
X741250Y-33092D01*
X742560Y-32800D01*
X743870Y-33383D01*
X744525Y-34842D01*
G01X741905Y-39800D02*
X737538D01*
G01X758750Y-38634D02*
Y-50300D01*
G01Y-33967D02*
X758313Y-33675D01*
Y-33092D01*
X758750Y-32800D01*
X759187Y-33092D01*
Y-33675D01*
X758750Y-33967D01*
G01X772538Y-50300D02*
Y-38634D01*
G01Y-41550D02*
X773412Y-40092D01*
X774722Y-38925D01*
X776468Y-38634D01*
X777996Y-38925D01*
X779307Y-40092D01*
X779962Y-42133D01*
Y-50300D01*
G01X797680Y-32800D02*
Y-50300D01*
G01Y-47676D02*
X796807Y-49134D01*
X795496Y-50008D01*
X793968Y-50300D01*
X792222Y-49717D01*
X790912Y-48259D01*
X790038Y-46509D01*
X789820Y-44467D01*
X790038Y-42425D01*
X790912Y-40675D01*
X792222Y-39217D01*
X793968Y-38634D01*
X795496Y-38925D01*
X796588Y-39509D01*
X797680Y-40675D01*
G01X828750Y-32800D02*
Y-50300D01*
G01X825693Y-38634D02*
X831807D01*
G01X842538Y-50300D02*
Y-32800D01*
G01Y-41258D02*
X843630Y-39800D01*
X844722Y-38925D01*
X846468Y-38634D01*
X847778Y-38925D01*
X849307Y-40092D01*
X849962Y-41842D01*
Y-50300D01*
G01X860475Y-42425D02*
X867462D01*
X866807Y-40383D01*
X865715Y-39217D01*
X864187Y-38634D01*
X862658Y-38925D01*
X861348Y-39800D01*
X860475Y-41842D01*
X860038Y-43592D01*
Y-45342D01*
X860475Y-47092D01*
X861567Y-48842D01*
X862877Y-50008D01*
X864405Y-50300D01*
X865933Y-49717D01*
X867462Y-47967D01*
G01X893947Y-50300D02*
Y-32800D01*
X898313D01*
X900060Y-33675D01*
X901370Y-34842D01*
X902462Y-36591D01*
X903335Y-38634D01*
X903553Y-41550D01*
X903335Y-44467D01*
X902462Y-46509D01*
X901370Y-48259D01*
X900060Y-49425D01*
X898313Y-50300D01*
X893947D01*
G01X911883D02*
Y-32800D01*
X917123D01*
X918870Y-33675D01*
X920180Y-35717D01*
X920617Y-38050D01*
X920180Y-40383D01*
X919088Y-42133D01*
X917123Y-43009D01*
X911883D01*
G01X951250Y-38634D02*
Y-50300D01*
G01Y-33967D02*
X950813Y-33675D01*
Y-33092D01*
X951250Y-32800D01*
X951687Y-33092D01*
Y-33675D01*
X951250Y-33967D01*
G01X962200Y-50300D02*
Y-38634D01*
G01Y-41842D02*
X962855Y-40383D01*
X963947Y-39217D01*
X965475Y-38634D01*
X967003Y-39217D01*
X968095Y-40383D01*
X968750Y-41842D01*
Y-50300D01*
G01Y-41842D02*
X969405Y-40383D01*
X970496Y-39217D01*
X972025Y-38634D01*
X973553Y-39217D01*
X974645Y-40383D01*
X975300Y-42133D01*
Y-50300D01*
G01X982320Y-56133D02*
Y-38634D01*
G01Y-41258D02*
X983412Y-39800D01*
X984503Y-38925D01*
X986250Y-38634D01*
X987778Y-38925D01*
X989307Y-40383D01*
X989962Y-42425D01*
X990180Y-44467D01*
X989962Y-46509D01*
X989307Y-48550D01*
X987996Y-49717D01*
X986250Y-50300D01*
X984722Y-50008D01*
X983193Y-49134D01*
X982320Y-47967D01*
G01X1000475Y-42425D02*
X1007462D01*
X1006807Y-40383D01*
X1005715Y-39217D01*
X1004187Y-38634D01*
X1002658Y-38925D01*
X1001348Y-39800D01*
X1000475Y-41842D01*
X1000038Y-43592D01*
Y-45342D01*
X1000475Y-47092D01*
X1001567Y-48842D01*
X1002877Y-50008D01*
X1004405Y-50300D01*
X1005933Y-49717D01*
X1007462Y-47967D01*
G01X1025180Y-32800D02*
Y-50300D01*
G01Y-47676D02*
X1024307Y-49134D01*
X1022996Y-50008D01*
X1021468Y-50300D01*
X1019722Y-49717D01*
X1018412Y-48259D01*
X1017538Y-46509D01*
X1017320Y-44467D01*
X1017538Y-42425D01*
X1018412Y-40675D01*
X1019722Y-39217D01*
X1021468Y-38634D01*
X1022996Y-38925D01*
X1024088Y-39509D01*
X1025180Y-40675D01*
G01X1042680Y-50300D02*
Y-38634D01*
G01Y-40675D02*
X1041807Y-39509D01*
X1040496Y-38925D01*
X1038968Y-38634D01*
X1037440Y-39217D01*
X1036130Y-40383D01*
X1035256Y-42133D01*
X1034820Y-44467D01*
X1035256Y-46800D01*
X1036130Y-48550D01*
X1037440Y-49717D01*
X1038968Y-50300D01*
X1040496Y-50008D01*
X1041807Y-49134D01*
X1042680Y-47967D01*
G01X1052538Y-50300D02*
Y-38634D01*
G01Y-41550D02*
X1053412Y-40092D01*
X1054722Y-38925D01*
X1056468Y-38634D01*
X1057996Y-38925D01*
X1059307Y-40092D01*
X1059962Y-42133D01*
Y-50300D01*
G01X1077243Y-40092D02*
X1075715Y-38925D01*
X1074405Y-38634D01*
X1072658Y-39217D01*
X1071348Y-40383D01*
X1070475Y-42425D01*
X1070256Y-44467D01*
X1070475Y-46509D01*
X1071348Y-48259D01*
X1072658Y-49717D01*
X1074405Y-50300D01*
X1075933Y-49717D01*
X1077243Y-48550D01*
G01X1087975Y-42425D02*
X1094962D01*
X1094307Y-40383D01*
X1093215Y-39217D01*
X1091687Y-38634D01*
X1090158Y-38925D01*
X1088848Y-39800D01*
X1087975Y-41842D01*
X1087538Y-43592D01*
Y-45342D01*
X1087975Y-47092D01*
X1089067Y-48842D01*
X1090377Y-50008D01*
X1091905Y-50300D01*
X1093433Y-49717D01*
X1094962Y-47967D01*
G01X1126250Y-32800D02*
Y-50300D01*
G01X1123193Y-38634D02*
X1129307D01*
G01X1140693Y-50300D02*
Y-38634D01*
G01Y-40967D02*
X1141785Y-39800D01*
X1142877Y-38925D01*
X1144405Y-38634D01*
X1145496Y-38925D01*
X1146807Y-39800D01*
G01X1165180Y-50300D02*
Y-38634D01*
G01Y-40675D02*
X1164307Y-39509D01*
X1162996Y-38925D01*
X1161468Y-38634D01*
X1159940Y-39217D01*
X1158630Y-40383D01*
X1157756Y-42133D01*
X1157320Y-44467D01*
X1157756Y-46800D01*
X1158630Y-48550D01*
X1159940Y-49717D01*
X1161468Y-50300D01*
X1162996Y-50008D01*
X1164307Y-49134D01*
X1165180Y-47967D01*
G01X1182243Y-40092D02*
X1180715Y-38925D01*
X1179405Y-38634D01*
X1177658Y-39217D01*
X1176348Y-40383D01*
X1175475Y-42425D01*
X1175256Y-44467D01*
X1175475Y-46509D01*
X1176348Y-48259D01*
X1177658Y-49717D01*
X1179405Y-50300D01*
X1180933Y-49717D01*
X1182243Y-48550D01*
G01X1192975Y-42425D02*
X1199962D01*
X1199307Y-40383D01*
X1198215Y-39217D01*
X1196687Y-38634D01*
X1195158Y-38925D01*
X1193848Y-39800D01*
X1192975Y-41842D01*
X1192538Y-43592D01*
Y-45342D01*
X1192975Y-47092D01*
X1194067Y-48842D01*
X1195377Y-50008D01*
X1196905Y-50300D01*
X1198433Y-49717D01*
X1199962Y-47967D01*
G01X1210475Y-48259D02*
X1211567Y-49425D01*
X1213095Y-50300D01*
X1214405D01*
X1215715Y-49717D01*
X1216588Y-48842D01*
X1217025Y-47676D01*
X1216807Y-45925D01*
X1215933Y-45050D01*
X1212003Y-43300D01*
X1211130Y-41258D01*
X1211567Y-39800D01*
X1212440Y-38925D01*
X1213750Y-38634D01*
X1215060Y-38925D01*
X1216370Y-39800D01*
G01X1248750Y-38634D02*
Y-50300D01*
G01Y-33967D02*
X1248313Y-33675D01*
Y-33092D01*
X1248750Y-32800D01*
X1249187Y-33092D01*
Y-33675D01*
X1248750Y-33967D01*
G01X1262538Y-50300D02*
Y-38634D01*
G01Y-41550D02*
X1263412Y-40092D01*
X1264722Y-38925D01*
X1266468Y-38634D01*
X1267996Y-38925D01*
X1269307Y-40092D01*
X1269962Y-42133D01*
Y-50300D01*
G01X1301250D02*
Y-32800D01*
G01X1322680Y-50300D02*
Y-38634D01*
G01Y-40675D02*
X1321807Y-39509D01*
X1320496Y-38925D01*
X1318968Y-38634D01*
X1317440Y-39217D01*
X1316130Y-40383D01*
X1315256Y-42133D01*
X1314820Y-44467D01*
X1315256Y-46800D01*
X1316130Y-48550D01*
X1317440Y-49717D01*
X1318968Y-50300D01*
X1320496Y-50008D01*
X1321807Y-49134D01*
X1322680Y-47967D01*
G01X1331665Y-55550D02*
X1332975Y-56133D01*
X1334722Y-55550D01*
X1335813Y-54384D01*
X1336687Y-52925D01*
X1337996Y-48259D01*
X1340835Y-38634D01*
G01X1333848D02*
X1337996Y-48259D01*
G01X1350475Y-42425D02*
X1357462D01*
X1356807Y-40383D01*
X1355715Y-39217D01*
X1354187Y-38634D01*
X1352658Y-38925D01*
X1351348Y-39800D01*
X1350475Y-41842D01*
X1350038Y-43592D01*
Y-45342D01*
X1350475Y-47092D01*
X1351567Y-48842D01*
X1352877Y-50008D01*
X1354405Y-50300D01*
X1355933Y-49717D01*
X1357462Y-47967D01*
G01X1368193Y-50300D02*
Y-38634D01*
G01Y-40967D02*
X1369285Y-39800D01*
X1370377Y-38925D01*
X1371905Y-38634D01*
X1372996Y-38925D01*
X1374307Y-39800D01*
G01X1401883Y-32800D02*
Y-50300D01*
X1410617D01*
G01X1419602Y-43009D02*
X1421130Y-40967D01*
X1422440Y-39800D01*
X1424187Y-39217D01*
X1425715Y-39800D01*
X1426807Y-40967D01*
X1427680Y-42717D01*
X1427898Y-44758D01*
X1427680Y-46509D01*
X1426807Y-48259D01*
X1425496Y-49717D01*
X1423968Y-50300D01*
X1422222Y-49717D01*
X1420693Y-47967D01*
X1419820Y-45342D01*
X1419602Y-42425D01*
X1420038Y-38634D01*
X1420693Y-36591D01*
X1421785Y-34550D01*
X1423313Y-33092D01*
X1424842Y-32800D01*
X1426370Y-33383D01*
X1427462Y-34842D01*
G01X1441250Y-50883D02*
X1440813Y-50592D01*
Y-50008D01*
X1441250Y-49717D01*
X1441687Y-50008D01*
Y-50592D01*
X1441250Y-50883D01*
G01X999127Y722030D02*
X1004367D01*
G01X1001747D02*
Y704530D01*
G01X999127D02*
X1004367D01*
G01X1013570D02*
Y722030D01*
X1019247Y707447D01*
X1024924Y722030D01*
Y704530D01*
G01X1032380D02*
Y722030D01*
X1037620D01*
X1039367Y721155D01*
X1040677Y719113D01*
X1041114Y716780D01*
X1040677Y714447D01*
X1039585Y712697D01*
X1037620Y711821D01*
X1032380D01*
G01X1053155Y698697D02*
X1050972Y701613D01*
X1049880Y704530D01*
Y716196D01*
X1050972Y719113D01*
X1053155Y722030D01*
G01X1071747Y704530D02*
X1070000Y704822D01*
X1068472Y705988D01*
X1067162Y707738D01*
X1066288Y709780D01*
X1065852Y712113D01*
Y714447D01*
X1066288Y716780D01*
X1067162Y718822D01*
X1068472Y720571D01*
X1070000Y721738D01*
X1071747Y722030D01*
X1073493Y721738D01*
X1075022Y720571D01*
X1076332Y718822D01*
X1077206Y716780D01*
X1077642Y714447D01*
Y712113D01*
X1077206Y709780D01*
X1076332Y707738D01*
X1075022Y705988D01*
X1073493Y704822D01*
X1071747Y704530D01*
G01X1085535D02*
Y722030D01*
G01Y713572D02*
X1086627Y715030D01*
X1087719Y715905D01*
X1089465Y716196D01*
X1090775Y715905D01*
X1092304Y714738D01*
X1092959Y712988D01*
Y704530D01*
G01X1100197D02*
Y716196D01*
G01Y712988D02*
X1100852Y714447D01*
X1101944Y715613D01*
X1103472Y716196D01*
X1105000Y715613D01*
X1106092Y714447D01*
X1106747Y712988D01*
Y704530D01*
G01Y712988D02*
X1107402Y714447D01*
X1108493Y715613D01*
X1110022Y716196D01*
X1111550Y715613D01*
X1112642Y714447D01*
X1113297Y712697D01*
Y704530D01*
G01X1125339Y698697D02*
X1127522Y701613D01*
X1128614Y704530D01*
Y716196D01*
X1127522Y719113D01*
X1125339Y722030D01*
G01X977244Y739180D02*
Y756680D01*
X981610D01*
X983357Y755805D01*
X984667Y754638D01*
X985759Y752889D01*
X986632Y750846D01*
X986850Y747930D01*
X986632Y745013D01*
X985759Y742971D01*
X984667Y741221D01*
X983357Y740055D01*
X981610Y739180D01*
X977244D01*
G01X995180D02*
Y756680D01*
X1000420D01*
X1002167Y755805D01*
X1003477Y753763D01*
X1003914Y751430D01*
X1003477Y749097D01*
X1002385Y747347D01*
X1000420Y746471D01*
X995180D01*
G01X1031927Y756680D02*
X1037167D01*
G01X1034547D02*
Y739180D01*
G01X1031927D02*
X1037167D01*
G01X1046370D02*
Y756680D01*
X1052047Y742097D01*
X1057724Y756680D01*
Y739180D01*
G01X1065180D02*
Y756680D01*
X1070420D01*
X1072167Y755805D01*
X1073477Y753763D01*
X1073914Y751430D01*
X1073477Y749097D01*
X1072385Y747347D01*
X1070420Y746471D01*
X1065180D01*
G01X1091414Y739180D02*
X1082680D01*
Y756680D01*
X1091414D01*
G01X1087920Y748222D02*
X1082680D01*
G01X1099744Y739180D02*
Y756680D01*
X1104110D01*
X1105857Y755805D01*
X1107167Y754638D01*
X1108259Y752889D01*
X1109132Y750846D01*
X1109350Y747930D01*
X1109132Y745013D01*
X1108259Y742971D01*
X1107167Y741221D01*
X1105857Y740055D01*
X1104110Y739180D01*
X1099744D01*
G01X1116588D02*
X1122047Y756680D01*
X1127506Y739180D01*
G01X1125540Y745305D02*
X1118553D01*
G01X1134525Y739180D02*
Y756680D01*
X1144569Y739180D01*
Y756680D01*
G01X1161850Y755221D02*
X1160540Y756097D01*
X1159012Y756680D01*
X1157265D01*
X1155300Y755805D01*
X1153772Y754347D01*
X1152680Y752596D01*
X1151807Y749680D01*
X1151588Y747055D01*
X1152025Y744430D01*
X1152680Y742680D01*
X1153990Y740930D01*
X1155519Y739763D01*
X1157047Y739180D01*
X1158575D01*
X1160104Y739763D01*
X1161414Y740638D01*
X1162506Y741804D01*
G01X1178914Y739180D02*
X1170180D01*
Y756680D01*
X1178914D01*
G01X1175420Y748222D02*
X1170180D01*
G01X1209547Y756680D02*
Y739180D01*
G01X1204525Y756680D02*
X1214569D01*
G01X1221588Y739180D02*
X1227047Y756680D01*
X1232506Y739180D01*
G01X1230540Y745305D02*
X1223553D01*
G01X1246293Y748513D02*
X1247167Y749388D01*
X1247822Y750846D01*
X1248259Y752889D01*
X1247822Y754638D01*
X1246949Y755805D01*
X1245420Y756680D01*
X1239525D01*
Y739180D01*
X1246730D01*
X1248259Y740346D01*
X1249132Y742097D01*
X1249569Y744138D01*
X1249132Y746180D01*
X1247822Y747930D01*
X1246293Y748513D01*
X1239525D01*
G01X1257680Y756680D02*
Y739180D01*
X1266414D01*
G01X1283914D02*
X1275180D01*
Y756680D01*
X1283914D01*
G01X1280420Y748222D02*
X1275180D01*
G01X1297047Y738597D02*
X1296610Y738888D01*
Y739472D01*
X1297047Y739763D01*
X1297484Y739472D01*
Y738888D01*
X1297047Y738597D01*
G01Y746471D02*
X1296610Y746763D01*
Y747347D01*
X1297047Y747638D01*
X1297484Y747347D01*
Y746763D01*
X1297047Y746471D01*
G01X1327680Y756680D02*
Y739180D01*
X1336414D01*
G01X1345399Y746471D02*
X1346927Y748513D01*
X1348237Y749680D01*
X1349984Y750263D01*
X1351512Y749680D01*
X1352604Y748513D01*
X1353477Y746763D01*
X1353695Y744722D01*
X1353477Y742971D01*
X1352604Y741221D01*
X1351293Y739763D01*
X1349765Y739180D01*
X1348019Y739763D01*
X1346490Y741513D01*
X1345617Y744138D01*
X1345399Y747055D01*
X1345835Y750846D01*
X1346490Y752889D01*
X1347582Y754930D01*
X1349110Y756388D01*
X1350639Y756680D01*
X1352167Y756097D01*
X1353259Y754638D01*
G01X1014444Y634647D02*
X1024050Y647480D01*
G01X1019247Y649813D02*
Y632313D01*
G01X1024050Y634647D02*
X1014444Y647480D01*
G01X1012697Y641063D02*
X1025797D01*
G01X1036747Y635230D02*
Y652730D01*
X1034127Y649230D01*
G01Y635230D02*
X1039367D01*
G01X1054247Y652730D02*
X1052500Y652147D01*
X1051190Y650688D01*
X1050317Y648939D01*
X1049662Y646605D01*
X1049444Y643980D01*
X1049662Y641355D01*
X1050317Y639021D01*
X1051190Y637271D01*
X1052500Y635813D01*
X1054247Y635230D01*
X1055993Y635813D01*
X1057304Y637271D01*
X1058177Y639021D01*
X1058832Y641355D01*
X1059050Y643980D01*
X1058832Y646605D01*
X1058177Y648939D01*
X1057304Y650688D01*
X1055993Y652147D01*
X1054247Y652730D01*
G01X1071747D02*
X1070000Y652147D01*
X1068690Y650688D01*
X1067817Y648939D01*
X1067162Y646605D01*
X1066944Y643980D01*
X1067162Y641355D01*
X1067817Y639021D01*
X1068690Y637271D01*
X1070000Y635813D01*
X1071747Y635230D01*
X1073493Y635813D01*
X1074804Y637271D01*
X1075677Y639021D01*
X1076332Y641355D01*
X1076550Y643980D01*
X1076332Y646605D01*
X1075677Y648939D01*
X1074804Y650688D01*
X1073493Y652147D01*
X1071747Y652730D01*
G01X1089247Y634647D02*
X1088810Y634938D01*
Y635522D01*
X1089247Y635813D01*
X1089684Y635522D01*
Y634938D01*
X1089247Y634647D01*
G01X1106747Y652730D02*
X1105000Y652147D01*
X1103690Y650688D01*
X1102817Y648939D01*
X1102162Y646605D01*
X1101944Y643980D01*
X1102162Y641355D01*
X1102817Y639021D01*
X1103690Y637271D01*
X1105000Y635813D01*
X1106747Y635230D01*
X1108493Y635813D01*
X1109804Y637271D01*
X1110677Y639021D01*
X1111332Y641355D01*
X1111550Y643980D01*
X1111332Y646605D01*
X1110677Y648939D01*
X1109804Y650688D01*
X1108493Y652147D01*
X1106747Y652730D01*
G01X1036747Y669880D02*
X1038275Y670172D01*
X1040022Y671046D01*
X1041114Y672504D01*
X1041550Y674547D01*
X1041114Y676588D01*
X1039804Y678338D01*
X1037839Y679213D01*
X1035655D01*
X1034345Y679797D01*
X1033253Y681255D01*
X1032817Y683296D01*
X1033472Y685338D01*
X1035000Y686797D01*
X1036747Y687380D01*
X1038493Y686797D01*
X1040022Y685338D01*
X1040677Y683296D01*
X1040240Y681255D01*
X1039149Y679797D01*
X1037839Y679213D01*
X1035655D01*
X1033690Y678338D01*
X1032380Y676588D01*
X1031944Y674547D01*
X1032380Y672504D01*
X1033472Y671046D01*
X1035219Y670172D01*
X1036747Y669880D01*
G01X1049444Y672504D02*
X1050753Y671046D01*
X1052282Y670172D01*
X1054247Y669880D01*
X1056212Y670463D01*
X1057740Y671630D01*
X1058832Y673671D01*
X1059050Y676005D01*
X1058614Y678338D01*
X1057522Y679797D01*
X1055993Y680963D01*
X1054465Y681255D01*
X1052937Y680963D01*
X1050972Y679797D01*
X1051627Y687380D01*
X1057522D01*
G01X1071747Y669297D02*
X1071310Y669588D01*
Y670172D01*
X1071747Y670463D01*
X1072184Y670172D01*
Y669588D01*
X1071747Y669297D01*
G01X1089247Y687380D02*
X1087500Y686797D01*
X1086190Y685338D01*
X1085317Y683589D01*
X1084662Y681255D01*
X1084444Y678630D01*
X1084662Y676005D01*
X1085317Y673671D01*
X1086190Y671921D01*
X1087500Y670463D01*
X1089247Y669880D01*
X1090993Y670463D01*
X1092304Y671921D01*
X1093177Y673671D01*
X1093832Y676005D01*
X1094050Y678630D01*
X1093832Y681255D01*
X1093177Y683589D01*
X1092304Y685338D01*
X1090993Y686797D01*
X1089247Y687380D01*
G01X1205197Y722030D02*
X1208253Y704530D01*
X1211747Y722030D01*
X1215240Y704530D01*
X1218297Y722030D01*
G01X1226627D02*
X1231867D01*
G01X1229247D02*
Y704530D01*
G01X1226627D02*
X1231867D01*
G01X1241944D02*
Y722030D01*
X1246310D01*
X1248057Y721155D01*
X1249367Y719988D01*
X1250459Y718239D01*
X1251332Y716196D01*
X1251550Y713280D01*
X1251332Y710363D01*
X1250459Y708321D01*
X1249367Y706571D01*
X1248057Y705405D01*
X1246310Y704530D01*
X1241944D01*
G01X1264247Y722030D02*
Y704530D01*
G01X1259225Y722030D02*
X1269269D01*
G01X1277162Y704530D02*
Y722030D01*
G01X1286332D02*
Y704530D01*
G01Y713280D02*
X1277162D01*
G01X1298155Y698697D02*
X1295972Y701613D01*
X1294880Y704530D01*
Y716196D01*
X1295972Y719113D01*
X1298155Y722030D01*
G01X1310197Y704530D02*
Y716196D01*
G01Y712988D02*
X1310852Y714447D01*
X1311944Y715613D01*
X1313472Y716196D01*
X1315000Y715613D01*
X1316092Y714447D01*
X1316747Y712988D01*
Y704530D01*
G01Y712988D02*
X1317402Y714447D01*
X1318493Y715613D01*
X1320022Y716196D01*
X1321550Y715613D01*
X1322642Y714447D01*
X1323297Y712697D01*
Y704530D01*
G01X1334247Y716196D02*
Y704530D01*
G01Y720863D02*
X1333810Y721155D01*
Y721738D01*
X1334247Y722030D01*
X1334684Y721738D01*
Y721155D01*
X1334247Y720863D01*
G01X1351747Y704530D02*
Y722030D01*
G01X1365972Y706571D02*
X1367064Y705405D01*
X1368592Y704530D01*
X1369902D01*
X1371212Y705113D01*
X1372085Y705988D01*
X1372522Y707154D01*
X1372304Y708905D01*
X1371430Y709780D01*
X1367500Y711530D01*
X1366627Y713572D01*
X1367064Y715030D01*
X1367937Y715905D01*
X1369247Y716196D01*
X1370557Y715905D01*
X1371867Y715030D01*
G01X1387839Y698697D02*
X1390022Y701613D01*
X1391114Y704530D01*
Y716196D01*
X1390022Y719113D01*
X1387839Y722030D01*
G01X1249367Y635230D02*
Y652730D01*
X1241288Y640188D01*
X1252206D01*
G01X1264247Y634647D02*
X1263810Y634938D01*
Y635522D01*
X1264247Y635813D01*
X1264684Y635522D01*
Y634938D01*
X1264247Y634647D01*
G01X1281747Y652730D02*
X1280000Y652147D01*
X1278690Y650688D01*
X1277817Y648939D01*
X1277162Y646605D01*
X1276944Y643980D01*
X1277162Y641355D01*
X1277817Y639021D01*
X1278690Y637271D01*
X1280000Y635813D01*
X1281747Y635230D01*
X1283493Y635813D01*
X1284804Y637271D01*
X1285677Y639021D01*
X1286332Y641355D01*
X1286550Y643980D01*
X1286332Y646605D01*
X1285677Y648939D01*
X1284804Y650688D01*
X1283493Y652147D01*
X1281747Y652730D01*
G01X1295317Y634647D02*
X1303177Y652730D01*
G01X1316747Y635230D02*
X1318275Y635522D01*
X1320022Y636396D01*
X1321114Y637854D01*
X1321550Y639897D01*
X1321114Y641938D01*
X1319804Y643688D01*
X1317839Y644563D01*
X1315655D01*
X1314345Y645147D01*
X1313253Y646605D01*
X1312817Y648646D01*
X1313472Y650688D01*
X1315000Y652147D01*
X1316747Y652730D01*
X1318493Y652147D01*
X1320022Y650688D01*
X1320677Y648646D01*
X1320240Y646605D01*
X1319149Y645147D01*
X1317839Y644563D01*
X1315655D01*
X1313690Y643688D01*
X1312380Y641938D01*
X1311944Y639897D01*
X1312380Y637854D01*
X1313472Y636396D01*
X1315219Y635522D01*
X1316747Y635230D01*
G01X1334247Y634647D02*
X1333810Y634938D01*
Y635522D01*
X1334247Y635813D01*
X1334684Y635522D01*
Y634938D01*
X1334247Y634647D01*
G01X1351747Y652730D02*
X1350000Y652147D01*
X1348690Y650688D01*
X1347817Y648939D01*
X1347162Y646605D01*
X1346944Y643980D01*
X1347162Y641355D01*
X1347817Y639021D01*
X1348690Y637271D01*
X1350000Y635813D01*
X1351747Y635230D01*
X1353493Y635813D01*
X1354804Y637271D01*
X1355677Y639021D01*
X1356332Y641355D01*
X1356550Y643980D01*
X1356332Y646605D01*
X1355677Y648939D01*
X1354804Y650688D01*
X1353493Y652147D01*
X1351747Y652730D01*
G01X1241944Y672504D02*
X1243253Y671046D01*
X1244782Y670172D01*
X1246747Y669880D01*
X1248712Y670463D01*
X1250240Y671630D01*
X1251332Y673671D01*
X1251550Y676005D01*
X1251114Y678338D01*
X1250022Y679797D01*
X1248493Y680963D01*
X1246965Y681255D01*
X1245437Y680963D01*
X1243472Y679797D01*
X1244127Y687380D01*
X1250022D01*
G01X1264247Y669297D02*
X1263810Y669588D01*
Y670172D01*
X1264247Y670463D01*
X1264684Y670172D01*
Y669588D01*
X1264247Y669297D01*
G01X1276944Y672504D02*
X1278253Y671046D01*
X1279782Y670172D01*
X1281747Y669880D01*
X1283712Y670463D01*
X1285240Y671630D01*
X1286332Y673671D01*
X1286550Y676005D01*
X1286114Y678338D01*
X1285022Y679797D01*
X1283493Y680963D01*
X1281965Y681255D01*
X1280437Y680963D01*
X1278472Y679797D01*
X1279127Y687380D01*
X1285022D01*
G01X1295317Y669297D02*
X1303177Y687380D01*
G01X1316310Y669880D02*
X1316747Y673671D01*
X1317402Y676880D01*
X1318275Y679797D01*
X1319367Y683005D01*
X1321114Y687380D01*
X1312380D01*
G01X1334247Y669297D02*
X1333810Y669588D01*
Y670172D01*
X1334247Y670463D01*
X1334684Y670172D01*
Y669588D01*
X1334247Y669297D01*
G01X1346944Y672504D02*
X1348253Y671046D01*
X1349782Y670172D01*
X1351747Y669880D01*
X1353712Y670463D01*
X1355240Y671630D01*
X1356332Y673671D01*
X1356550Y676005D01*
X1356114Y678338D01*
X1355022Y679797D01*
X1353493Y680963D01*
X1351965Y681255D01*
X1350437Y680963D01*
X1348472Y679797D01*
X1349127Y687380D01*
X1355022D01*
G01X1486944Y635230D02*
Y652730D01*
X1491310D01*
X1493057Y651855D01*
X1494367Y650688D01*
X1495459Y648939D01*
X1496332Y646896D01*
X1496550Y643980D01*
X1496332Y641063D01*
X1495459Y639021D01*
X1494367Y637271D01*
X1493057Y636105D01*
X1491310Y635230D01*
X1486944D01*
G01X1504880D02*
Y652730D01*
X1510120D01*
X1511867Y651855D01*
X1513177Y649813D01*
X1513614Y647480D01*
X1513177Y645147D01*
X1512085Y643397D01*
X1510120Y642521D01*
X1504880D01*
G01X1474247Y722030D02*
Y704530D01*
G01X1469225Y722030D02*
X1479269D01*
G01X1491747Y704530D02*
Y712405D01*
X1487380Y722030D01*
G01X1496114D02*
X1491747Y712405D01*
G01X1504880Y704530D02*
Y722030D01*
X1510120D01*
X1511867Y721155D01*
X1513177Y719113D01*
X1513614Y716780D01*
X1513177Y714447D01*
X1512085Y712697D01*
X1510120Y711821D01*
X1504880D01*
G01X1531114Y704530D02*
X1522380D01*
Y722030D01*
X1531114D01*
G01X1527620Y713572D02*
X1522380D01*
G01X1486944Y669880D02*
Y687380D01*
X1491310D01*
X1493057Y686505D01*
X1494367Y685338D01*
X1495459Y683589D01*
X1496332Y681546D01*
X1496550Y678630D01*
X1496332Y675713D01*
X1495459Y673671D01*
X1494367Y671921D01*
X1493057Y670755D01*
X1491310Y669880D01*
X1486944D01*
G01X1504880D02*
Y687380D01*
X1510120D01*
X1511867Y686505D01*
X1513177Y684463D01*
X1513614Y682130D01*
X1513177Y679797D01*
X1512085Y678047D01*
X1510120Y677171D01*
X1504880D01*
G01X1574880Y704530D02*
Y722030D01*
X1580339D01*
X1582085Y721155D01*
X1583177Y719988D01*
X1583614Y717655D01*
X1583177Y715321D01*
X1581867Y713863D01*
X1580339Y712988D01*
X1574880D01*
G01X1580339D02*
X1583614Y704530D01*
G01X1593472Y712405D02*
X1600459D01*
X1599804Y714447D01*
X1598712Y715613D01*
X1597184Y716196D01*
X1595655Y715905D01*
X1594345Y715030D01*
X1593472Y712988D01*
X1593035Y711238D01*
Y709488D01*
X1593472Y707738D01*
X1594564Y705988D01*
X1595874Y704822D01*
X1597402Y704530D01*
X1598930Y705113D01*
X1600459Y706863D01*
G01X1612937Y704530D02*
Y719405D01*
X1613374Y720863D01*
X1614247Y721738D01*
X1615557Y722030D01*
X1616867Y721447D01*
X1617522Y719988D01*
G01X1614902Y715030D02*
X1610535D01*
G01X1631747Y703947D02*
X1631310Y704238D01*
Y704822D01*
X1631747Y705113D01*
X1632184Y704822D01*
Y704238D01*
X1631747Y703947D01*
G01X1662380Y704530D02*
Y722030D01*
X1667620D01*
X1669367Y721155D01*
X1670677Y719113D01*
X1671114Y716780D01*
X1670677Y714447D01*
X1669585Y712697D01*
X1667620Y711821D01*
X1662380D01*
G01X1684247Y704530D02*
Y722030D01*
G01X1705677Y704530D02*
Y716196D01*
G01Y714155D02*
X1704804Y715321D01*
X1703493Y715905D01*
X1701965Y716196D01*
X1700437Y715613D01*
X1699127Y714447D01*
X1698253Y712697D01*
X1697817Y710363D01*
X1698253Y708030D01*
X1699127Y706280D01*
X1700437Y705113D01*
X1701965Y704530D01*
X1703493Y704822D01*
X1704804Y705696D01*
X1705677Y706863D01*
G01X1715535Y704530D02*
Y716196D01*
G01Y713280D02*
X1716409Y714738D01*
X1717719Y715905D01*
X1719465Y716196D01*
X1720993Y715905D01*
X1722304Y714738D01*
X1722959Y712697D01*
Y704530D01*
G01X1733472Y712405D02*
X1740459D01*
X1739804Y714447D01*
X1738712Y715613D01*
X1737184Y716196D01*
X1735655Y715905D01*
X1734345Y715030D01*
X1733472Y712988D01*
X1733035Y711238D01*
Y709488D01*
X1733472Y707738D01*
X1734564Y705988D01*
X1735874Y704822D01*
X1737402Y704530D01*
X1738930Y705113D01*
X1740459Y706863D01*
G01X1618630Y652730D02*
Y635230D01*
X1627364D01*
G01X1635694Y637854D02*
X1637003Y636396D01*
X1638532Y635522D01*
X1640497Y635230D01*
X1642462Y635813D01*
X1643990Y636980D01*
X1645082Y639021D01*
X1645300Y641355D01*
X1644864Y643688D01*
X1643772Y645147D01*
X1642243Y646313D01*
X1640715Y646605D01*
X1639187Y646313D01*
X1637222Y645147D01*
X1637877Y652730D01*
X1643772D01*
G01X1654067Y634647D02*
X1661927Y652730D01*
G01X1671130D02*
Y635230D01*
X1679864D01*
G01X1692560D02*
X1692997Y639021D01*
X1693652Y642230D01*
X1694525Y645147D01*
X1695617Y648355D01*
X1697364Y652730D01*
X1688630D01*
G01X1618630Y687380D02*
Y669880D01*
X1627364D01*
G01X1635694Y672504D02*
X1637003Y671046D01*
X1638532Y670172D01*
X1640497Y669880D01*
X1642462Y670463D01*
X1643990Y671630D01*
X1645082Y673671D01*
X1645300Y676005D01*
X1644864Y678338D01*
X1643772Y679797D01*
X1642243Y680963D01*
X1640715Y681255D01*
X1639187Y680963D01*
X1637222Y679797D01*
X1637877Y687380D01*
X1643772D01*
G01X1654067Y669297D02*
X1661927Y687380D01*
G01X1671130D02*
Y669880D01*
X1679864D01*
G01X1692560D02*
X1692997Y673671D01*
X1693652Y676880D01*
X1694525Y679797D01*
X1695617Y683005D01*
X1697364Y687380D01*
X1688630D01*
G01X1779744Y703947D02*
X1789350Y716780D01*
G01X1784547Y719113D02*
Y701613D01*
G01X1789350Y703947D02*
X1779744Y716780D01*
G01X1777997Y710363D02*
X1791097D01*
G01X1816709D02*
X1822385D01*
G01X1849744Y704530D02*
Y722030D01*
X1854110D01*
X1855857Y721155D01*
X1857167Y719988D01*
X1858259Y718239D01*
X1859132Y716196D01*
X1859350Y713280D01*
X1859132Y710363D01*
X1858259Y708321D01*
X1857167Y706571D01*
X1855857Y705405D01*
X1854110Y704530D01*
X1849744D01*
G01X1868772Y712405D02*
X1875759D01*
X1875104Y714447D01*
X1874012Y715613D01*
X1872484Y716196D01*
X1870955Y715905D01*
X1869645Y715030D01*
X1868772Y712988D01*
X1868335Y711238D01*
Y709488D01*
X1868772Y707738D01*
X1869864Y705988D01*
X1871174Y704822D01*
X1872702Y704530D01*
X1874230Y705113D01*
X1875759Y706863D01*
G01X1885835Y704530D02*
Y716196D01*
G01Y713280D02*
X1886709Y714738D01*
X1888019Y715905D01*
X1889765Y716196D01*
X1891293Y715905D01*
X1892604Y714738D01*
X1893259Y712697D01*
Y704530D01*
G01X1907047D02*
X1905737Y704822D01*
X1904427Y705988D01*
X1903553Y708030D01*
X1903117Y710363D01*
X1903553Y712697D01*
X1904427Y714738D01*
X1905737Y715905D01*
X1907047Y716196D01*
X1908357Y715905D01*
X1909667Y714738D01*
X1910540Y712697D01*
X1910759Y710363D01*
X1910540Y708030D01*
X1909667Y705988D01*
X1908357Y704822D01*
X1907047Y704530D01*
G01X1924547Y722030D02*
Y704530D01*
G01X1921490Y716196D02*
X1927604D01*
G01X1938772Y712405D02*
X1945759D01*
X1945104Y714447D01*
X1944012Y715613D01*
X1942484Y716196D01*
X1940955Y715905D01*
X1939645Y715030D01*
X1938772Y712988D01*
X1938335Y711238D01*
Y709488D01*
X1938772Y707738D01*
X1939864Y705988D01*
X1941174Y704822D01*
X1942702Y704530D01*
X1944230Y705113D01*
X1945759Y706863D01*
G01X1956272Y706571D02*
X1957364Y705405D01*
X1958892Y704530D01*
X1960202D01*
X1961512Y705113D01*
X1962385Y705988D01*
X1962822Y707154D01*
X1962604Y708905D01*
X1961730Y709780D01*
X1957800Y711530D01*
X1956927Y713572D01*
X1957364Y715030D01*
X1958237Y715905D01*
X1959547Y716196D01*
X1960857Y715905D01*
X1962167Y715030D01*
G01X1994547Y722030D02*
Y704530D01*
G01X1991490Y716196D02*
X1997604D01*
G01X2008335Y704530D02*
Y722030D01*
G01Y713572D02*
X2009427Y715030D01*
X2010519Y715905D01*
X2012265Y716196D01*
X2013575Y715905D01*
X2015104Y714738D01*
X2015759Y712988D01*
Y704530D01*
G01X2033477D02*
Y716196D01*
G01Y714155D02*
X2032604Y715321D01*
X2031293Y715905D01*
X2029765Y716196D01*
X2028237Y715613D01*
X2026927Y714447D01*
X2026053Y712697D01*
X2025617Y710363D01*
X2026053Y708030D01*
X2026927Y706280D01*
X2028237Y705113D01*
X2029765Y704530D01*
X2031293Y704822D01*
X2032604Y705696D01*
X2033477Y706863D01*
G01X2047047Y722030D02*
Y704530D01*
G01X2043990Y716196D02*
X2050104D01*
G01X2082047Y722030D02*
Y704530D01*
G01X2078990Y716196D02*
X2085104D01*
G01X2095835Y704530D02*
Y722030D01*
G01Y713572D02*
X2096927Y715030D01*
X2098019Y715905D01*
X2099765Y716196D01*
X2101075Y715905D01*
X2102604Y714738D01*
X2103259Y712988D01*
Y704530D01*
G01X2117047Y716196D02*
Y704530D01*
G01Y720863D02*
X2116610Y721155D01*
Y721738D01*
X2117047Y722030D01*
X2117484Y721738D01*
Y721155D01*
X2117047Y720863D01*
G01X2131272Y706571D02*
X2132364Y705405D01*
X2133892Y704530D01*
X2135202D01*
X2136512Y705113D01*
X2137385Y705988D01*
X2137822Y707154D01*
X2137604Y708905D01*
X2136730Y709780D01*
X2132800Y711530D01*
X2131927Y713572D01*
X2132364Y715030D01*
X2133237Y715905D01*
X2134547Y716196D01*
X2135857Y715905D01*
X2137167Y715030D01*
G01X2166927Y722030D02*
X2172167D01*
G01X2169547D02*
Y704530D01*
G01X2166927D02*
X2172167D01*
G01X2180497D02*
Y716196D01*
G01Y712988D02*
X2181152Y714447D01*
X2182244Y715613D01*
X2183772Y716196D01*
X2185300Y715613D01*
X2186392Y714447D01*
X2187047Y712988D01*
Y704530D01*
G01Y712988D02*
X2187702Y714447D01*
X2188793Y715613D01*
X2190322Y716196D01*
X2191850Y715613D01*
X2192942Y714447D01*
X2193597Y712697D01*
Y704530D01*
G01X2200617Y698697D02*
Y716196D01*
G01Y713572D02*
X2201709Y715030D01*
X2202800Y715905D01*
X2204547Y716196D01*
X2206075Y715905D01*
X2207604Y714447D01*
X2208259Y712405D01*
X2208477Y710363D01*
X2208259Y708321D01*
X2207604Y706280D01*
X2206293Y705113D01*
X2204547Y704530D01*
X2203019Y704822D01*
X2201490Y705696D01*
X2200617Y706863D01*
G01X2218772Y712405D02*
X2225759D01*
X2225104Y714447D01*
X2224012Y715613D01*
X2222484Y716196D01*
X2220955Y715905D01*
X2219645Y715030D01*
X2218772Y712988D01*
X2218335Y711238D01*
Y709488D01*
X2218772Y707738D01*
X2219864Y705988D01*
X2221174Y704822D01*
X2222702Y704530D01*
X2224230Y705113D01*
X2225759Y706863D01*
G01X2243477Y722030D02*
Y704530D01*
G01Y707154D02*
X2242604Y705696D01*
X2241293Y704822D01*
X2239765Y704530D01*
X2238019Y705113D01*
X2236709Y706571D01*
X2235835Y708321D01*
X2235617Y710363D01*
X2235835Y712405D01*
X2236709Y714155D01*
X2238019Y715613D01*
X2239765Y716196D01*
X2241293Y715905D01*
X2242385Y715321D01*
X2243477Y714155D01*
G01X2260977Y704530D02*
Y716196D01*
G01Y714155D02*
X2260104Y715321D01*
X2258793Y715905D01*
X2257265Y716196D01*
X2255737Y715613D01*
X2254427Y714447D01*
X2253553Y712697D01*
X2253117Y710363D01*
X2253553Y708030D01*
X2254427Y706280D01*
X2255737Y705113D01*
X2257265Y704530D01*
X2258793Y704822D01*
X2260104Y705696D01*
X2260977Y706863D01*
G01X2270835Y704530D02*
Y716196D01*
G01Y713280D02*
X2271709Y714738D01*
X2273019Y715905D01*
X2274765Y716196D01*
X2276293Y715905D01*
X2277604Y714738D01*
X2278259Y712697D01*
Y704530D01*
G01X2295540Y714738D02*
X2294012Y715905D01*
X2292702Y716196D01*
X2290955Y715613D01*
X2289645Y714447D01*
X2288772Y712405D01*
X2288553Y710363D01*
X2288772Y708321D01*
X2289645Y706571D01*
X2290955Y705113D01*
X2292702Y704530D01*
X2294230Y705113D01*
X2295540Y706280D01*
G01X2306272Y712405D02*
X2313259D01*
X2312604Y714447D01*
X2311512Y715613D01*
X2309984Y716196D01*
X2308455Y715905D01*
X2307145Y715030D01*
X2306272Y712988D01*
X2305835Y711238D01*
Y709488D01*
X2306272Y707738D01*
X2307364Y705988D01*
X2308674Y704822D01*
X2310202Y704530D01*
X2311730Y705113D01*
X2313259Y706863D01*
G01X1854547Y681546D02*
Y669880D01*
G01Y686213D02*
X1854110Y686505D01*
Y687088D01*
X1854547Y687380D01*
X1854984Y687088D01*
Y686505D01*
X1854547Y686213D01*
G01X1868772Y671921D02*
X1869864Y670755D01*
X1871392Y669880D01*
X1872702D01*
X1874012Y670463D01*
X1874885Y671338D01*
X1875322Y672504D01*
X1875104Y674255D01*
X1874230Y675130D01*
X1870300Y676880D01*
X1869427Y678922D01*
X1869864Y680380D01*
X1870737Y681255D01*
X1872047Y681546D01*
X1873357Y681255D01*
X1874667Y680380D01*
G01X1902025Y669880D02*
Y687380D01*
X1912069Y669880D01*
Y687380D01*
G01X1924547Y669880D02*
X1922800Y670172D01*
X1921272Y671338D01*
X1919962Y673088D01*
X1919088Y675130D01*
X1918652Y677463D01*
Y679797D01*
X1919088Y682130D01*
X1919962Y684172D01*
X1921272Y685921D01*
X1922800Y687088D01*
X1924547Y687380D01*
X1926293Y687088D01*
X1927822Y685921D01*
X1929132Y684172D01*
X1930006Y682130D01*
X1930442Y679797D01*
Y677463D01*
X1930006Y675130D01*
X1929132Y673088D01*
X1927822Y671338D01*
X1926293Y670172D01*
X1924547Y669880D01*
G01X1942047Y687380D02*
Y669880D01*
G01X1937025Y687380D02*
X1947069D01*
G01X1973335Y681546D02*
Y673380D01*
X1974209Y671338D01*
X1975519Y670172D01*
X1977047Y669880D01*
X1978575Y670172D01*
X1979885Y671338D01*
X1980759Y673380D01*
G01Y669880D02*
Y681546D01*
G01X1991272Y671921D02*
X1992364Y670755D01*
X1993892Y669880D01*
X1995202D01*
X1996512Y670463D01*
X1997385Y671338D01*
X1997822Y672504D01*
X1997604Y674255D01*
X1996730Y675130D01*
X1992800Y676880D01*
X1991927Y678922D01*
X1992364Y680380D01*
X1993237Y681255D01*
X1994547Y681546D01*
X1995857Y681255D01*
X1997167Y680380D01*
G01X2008772Y677755D02*
X2015759D01*
X2015104Y679797D01*
X2014012Y680963D01*
X2012484Y681546D01*
X2010955Y681255D01*
X2009645Y680380D01*
X2008772Y678338D01*
X2008335Y676588D01*
Y674838D01*
X2008772Y673088D01*
X2009864Y671338D01*
X2011174Y670172D01*
X2012702Y669880D01*
X2014230Y670463D01*
X2015759Y672213D01*
G01X2033477Y687380D02*
Y669880D01*
G01Y672504D02*
X2032604Y671046D01*
X2031293Y670172D01*
X2029765Y669880D01*
X2028019Y670463D01*
X2026709Y671921D01*
X2025835Y673671D01*
X2025617Y675713D01*
X2025835Y677755D01*
X2026709Y679505D01*
X2028019Y680963D01*
X2029765Y681546D01*
X2031293Y681255D01*
X2032385Y680671D01*
X2033477Y679505D01*
G01X3937Y0D02*
X116260D01*
G01X0Y3937D02*
G03X3937Y0I3937J0D01*
G01X0Y723480D02*
Y3937D01*
G01X416Y725241D02*
G03X0Y723480I3521J-1761D01*
G01X18597Y761603D02*
X416Y725241D01*
G01X22118Y763780D02*
G03X18597Y761603I1J-3937D01*
G01X386149Y763780D02*
X22118D01*
G01X120197Y3937D02*
Y429331D01*
G01X116260Y0D02*
G03X120197Y3937I0J3937D01*
G01X128071D02*
G03X132008Y0I3937J0D01*
G01X128071Y43308D02*
G03X120197I-3937J0D01*
G01X132008Y0D02*
X275709D01*
G01X128071Y3937D02*
Y43308D01*
G01X120197Y74016D02*
G03X128071I3937J0D01*
G01D02*
Y425394D01*
G01X124134Y433268D02*
X283583D01*
G01X124134D02*
G03X120197Y429331I0J-3937D01*
G01X188504Y425394D02*
X128071D01*
G01X152497Y21054D02*
G03I-4291J0D01*
G01X188504Y425394D02*
G03Y433268I0J3937D01*
G01X275709Y0D02*
G03X279646Y3937I0J3937D01*
G01X287520Y43308D02*
G03X279646I-3937J0D01*
G01Y3937D02*
Y43308D01*
G01Y74016D02*
G03X287520I3937J0D01*
G01X279646D02*
Y425394D01*
G01X265438Y405580D02*
G03I-4291J0D01*
G01X287520Y429331D02*
G03X283583Y433268I-3937J0D01*
G01X219213D02*
G03Y425394I0J-3937D01*
G01X279646D02*
X219213D01*
G01X291457Y0D02*
X921260D01*
G01X287520Y3937D02*
G03X291457Y0I3937J0D01*
G01X287520Y429331D02*
Y3937D01*
G01X408268Y188976D02*
Y723480D01*
G01Y188976D02*
G03X412205I1968J0D01*
G01X564173D02*
X412205D01*
G01X416142Y348379D02*
Y196851D01*
G01D02*
X560237D01*
G01X416142Y348379D02*
G03X408268I-3937J0D01*
G01Y379088D02*
G03X416142I3937J0D01*
G01Y688303D02*
Y379088D01*
G01Y688303D02*
G03X408268I-3937J0D01*
G01X389671Y761603D02*
G03X386149Y763780I-3522J-1760D01*
G01X407852Y725241D02*
X389671Y761603D01*
G01X408268Y723480D02*
G03X407852Y725241I-3937J0D01*
G01X524242Y763780D02*
X403757D01*
G01D02*
G03X400235Y758082I0J-3937D01*
G01X408268Y719012D02*
G03X416142I3937J0D01*
G01Y723480D02*
G03X414895Y728763I-11811J1D01*
G01X400235Y758082D02*
X414895Y728763D01*
G01X416142Y723480D02*
Y719012D01*
G01X490789Y356293D02*
G03I-4291J0D01*
G01X564173Y188976D02*
G03X568110I1968J0D01*
G01Y589622D02*
Y188976D01*
G01X560237Y261975D02*
Y196851D01*
G01X568111Y261975D02*
G03X560237I-3937J0D01*
G01Y292684D02*
G03X568111I3937J0D01*
G01X560237Y551040D02*
Y292684D01*
G01X568111Y551040D02*
G03X560237I-3937J0D01*
G01X568526Y591382D02*
G03X568110Y589622I3521J-1761D01*
G01X586707Y627745D02*
X568526Y591382D01*
G01X560237Y581748D02*
G03X568111I3937J0D01*
G01X561484Y594905D02*
G03X560237Y589622I10564J-5282D01*
G01D02*
Y581748D01*
G01X579665Y631267D02*
X561484Y594904D01*
G01X524242Y763780D02*
G03X532116I3937J0D01*
G01X834646D02*
X532116D01*
G01X590228Y629921D02*
G03X586707Y627745I0J-3937D01*
G01X842520Y629921D02*
X590228D01*
G01X590229Y637796D02*
G03X579665Y631268I0J-11812D01*
G01X590229Y637796D02*
X838583D01*
G01X842520Y629921D02*
G03X846457Y633858I0J3937D01*
G01Y759843D02*
Y633858D01*
G01X838583Y637796D02*
Y709449D01*
G01X850394Y763780D02*
G03X846457Y759843I0J-3937D01*
G01X903079Y763780D02*
X850394D01*
G01X812123Y734367D02*
G03I-4292J0D01*
G01X838583Y759843D02*
G03X834646Y763780I-3937J0D01*
G01X838583Y740158D02*
G03X846457I3937J0D01*
G01Y709449D02*
G03X838583I-3937J0D01*
G01Y740158D02*
Y759843D01*
G01X921260Y0D02*
G03X925197Y3937I0J3937D01*
G01D02*
Y723480D01*
G01X906600Y761603D02*
G03X903079Y763780I-3522J-1760D01*
G01X924781Y725241D02*
X906600Y761603D01*
G01X925197Y723480D02*
G03X924781Y725241I-3937J0D01*
G54D12*
G01X263407Y605625D02*
X290624D01*
G01X262868Y604325D02*
X291163D01*
G01X260732Y608300D02*
X263407Y605625D01*
G01X260193Y607000D02*
X262868Y604325D01*
G01X259582Y608300D02*
X260732D01*
G01X259483Y607000D02*
X260193D01*
G01X262868Y604325D02*
X291163D01*
G01X263407Y605625D02*
X290624D01*
G01X260193Y607000D02*
X262868Y604325D01*
G01X260732Y608300D02*
X263407Y605625D01*
G01X259483Y607000D02*
X260193D01*
G01X259582Y608300D02*
X260732D01*
G01X258307Y601594D02*
X293441D01*
G01X258471Y600294D02*
X293980D01*
G01X258471D02*
X293980D01*
G01X258307Y601594D02*
X293441D01*
G01X354848Y202606D02*
X359615Y225039D01*
G01X356664Y194065D02*
X354848Y202606D01*
G01D02*
X359615Y225039D01*
G01X356664Y194065D02*
X354848Y202606D01*
G01X347750Y191669D02*
X354779Y224732D01*
G01X349080Y191669D02*
X356108Y224731D01*
G01X352123Y171100D02*
X347750Y191669D01*
G01X353345Y171606D02*
X349080Y191669D01*
G01X359667Y159483D02*
X352123Y171100D01*
G01X360889Y159989D02*
X353345Y171606D01*
G01X349080Y191669D02*
X356108Y224731D01*
G01X347750Y191669D02*
X354779Y224732D01*
G01X353345Y171606D02*
X349080Y191669D01*
G01X352123Y171100D02*
X347750Y191669D01*
G01X360889Y159989D02*
X353345Y171606D01*
G01X359667Y159483D02*
X352123Y171100D01*
G01X365190Y217260D02*
X349541Y293519D01*
G01X366519Y217255D02*
X350766Y294021D01*
G01X366519Y217255D02*
X350766Y294021D01*
G01X365190Y217260D02*
X349541Y293519D01*
G01X348347Y277990D02*
X341022Y289270D01*
G01X360945Y225039D02*
X349569Y278496D01*
G01X359615Y225039D02*
X348347Y277990D01*
G01D02*
X341022Y289270D01*
G01X359615Y225039D02*
X348347Y277990D01*
G01X360945Y225039D02*
X349569Y278496D01*
G01X343875Y276540D02*
X341300Y281694D01*
G01X345113Y276971D02*
X342369Y282464D01*
G01X354779Y224732D02*
X343875Y276540D01*
G01X356108Y224731D02*
X345113Y276971D01*
G01D02*
X342369Y282464D01*
G01X343875Y276540D02*
X341300Y281694D01*
G01X356108Y224731D02*
X345113Y276971D01*
G01X354779Y224732D02*
X343875Y276540D01*
G01X357450Y342911D02*
X339787Y360574D01*
G01X358644Y343556D02*
X340326Y361874D01*
G01X358644Y343556D02*
X340326Y361874D01*
G01X357450Y342911D02*
X339787Y360574D01*
G01X335700Y347900D02*
X329271D01*
G01X336239Y349200D02*
X329303D01*
G01X356397Y327204D02*
X335700Y347900D01*
G01X357591Y327849D02*
X336239Y349200D01*
G01D02*
X329303D01*
G01X335700Y347900D02*
X329271D01*
G01X357591Y327849D02*
X336239Y349200D01*
G01X356397Y327204D02*
X335700Y347900D01*
G01X341479Y335321D02*
X335682D01*
G01X342018Y336621D02*
X335682D01*
G01X352736Y324064D02*
X341479Y335321D01*
G01X353928Y324711D02*
X342018Y336621D01*
G01X377458Y207731D02*
X352736Y324064D01*
G01X378788Y207731D02*
X353928Y324711D01*
G01X342018Y336621D02*
X335682D01*
G01X341479Y335321D02*
X335682D01*
G01X353928Y324711D02*
X342018Y336621D01*
G01X352736Y324064D02*
X341479Y335321D01*
G01X378788Y207731D02*
X353928Y324711D01*
G01X377458Y207731D02*
X352736Y324064D01*
G01X333805Y322700D02*
X329258D01*
G01X334344Y324000D02*
X329306D01*
G01X341092Y315413D02*
X333805Y322700D01*
G01X342103Y316242D02*
X334344Y324000D01*
G01X355614Y293629D02*
X341092Y315413D01*
G01X356838Y294139D02*
X342103Y316242D01*
G01X371309Y216773D02*
X355614Y293629D01*
G01X334344Y324000D02*
X329306D01*
G01X333805Y322700D02*
X329258D01*
G01X342103Y316242D02*
X334344Y324000D01*
G01X341092Y315413D02*
X333805Y322700D01*
G01X356838Y294139D02*
X342103Y316242D01*
G01X355614Y293629D02*
X341092Y315413D01*
G01X371309Y216773D02*
X355614Y293629D01*
G01X337677Y310184D02*
X335693D01*
G01X338216Y311484D02*
X335693D01*
G01X340645Y307216D02*
X337677Y310184D01*
G01X341661Y308039D02*
X338216Y311484D01*
G01X349541Y293519D02*
X340645Y307216D01*
G01X350766Y294021D02*
X341661Y308039D01*
G01X338216Y311484D02*
X335693D01*
G01X337677Y310184D02*
X335693D01*
G01X341661Y308039D02*
X338216Y311484D01*
G01X340645Y307216D02*
X337677Y310184D01*
G01X350766Y294021D02*
X341661Y308039D01*
G01X349541Y293519D02*
X340645Y307216D01*
G01X333226Y298905D02*
X329254D01*
G01X332687Y297605D02*
X329310D01*
G01X342038Y290093D02*
X333226Y298905D01*
G01X341022Y289270D02*
X332687Y297605D01*
G01X349569Y278496D02*
X342038Y290093D01*
G01X332687Y297605D02*
X329310D01*
G01X333226Y298905D02*
X329254D01*
G01X341022Y289270D02*
X332687Y297605D01*
G01X342038Y290093D02*
X333226Y298905D01*
G01X349569Y278496D02*
X342038Y290093D01*
G01X338038Y284954D02*
X335207D01*
G01X338577Y286254D02*
X335207D01*
G01X341300Y281694D02*
X338038Y284954D01*
G01X342369Y282464D02*
X338577Y286254D01*
G01D02*
X335207D01*
G01X338038Y284954D02*
X335207D01*
G01X342369Y282464D02*
X338577Y286254D01*
G01X341300Y281694D02*
X338038Y284954D01*
G01X336382Y373118D02*
X329282D01*
G01X336921Y374418D02*
X329282D01*
G01X359639Y349861D02*
X336382Y373118D01*
G01X360832Y350507D02*
X336921Y374418D01*
G01D02*
X329282D01*
G01X336382Y373118D02*
X329282D01*
G01X360832Y350507D02*
X336921Y374418D01*
G01X359639Y349861D02*
X336382Y373118D01*
G01X339787Y360574D02*
X335682D01*
G01X340326Y361874D02*
X335682D01*
G01X340326D02*
X335682D01*
G01X339787Y360574D02*
X335682D01*
G01X336671Y605923D02*
Y603790D01*
G01X335371Y605384D02*
Y603755D01*
G01X334970Y607624D02*
X336671Y605923D01*
G01X334431Y606324D02*
X335371Y605384D01*
G01X332921Y607624D02*
X334970D01*
G01X332382Y606324D02*
X334431D01*
G01X325537Y615008D02*
X332921Y607624D01*
G01X324998Y613708D02*
X332382Y606324D01*
G01X300007Y615008D02*
X325537D01*
G01X323348Y613708D02*
X324998D01*
G01X318648D02*
X320298D01*
G01X313948D02*
X315598D01*
G01X309248D02*
X310898D01*
G01X300546D02*
X306198D01*
G01X290624Y605625D02*
X300007Y615008D01*
G01X299379Y612541D02*
X300546Y613708D01*
G01X297223Y610385D02*
X298213D01*
G01X296056Y609218D02*
X297223Y610385D01*
G01X293900Y607062D02*
X294890D01*
G01X291163Y604325D02*
X293900Y607062D01*
G01X335371Y605384D02*
Y603755D01*
G01X336671Y605923D02*
Y603790D01*
G01X334431Y606324D02*
X335371Y605384D01*
G01X334970Y607624D02*
X336671Y605923D01*
G01X332382Y606324D02*
X334431D01*
G01X332921Y607624D02*
X334970D01*
G01X324998Y613708D02*
X332382Y606324D01*
G01X325537Y615008D02*
X332921Y607624D01*
G01X323348Y613708D02*
X324998D01*
G01X300007Y615008D02*
X325537D01*
G01X318648Y613708D02*
X320298D01*
G01X300007Y615008D02*
X325537D01*
G01X313948Y613708D02*
X315598D01*
G01X300007Y615008D02*
X325537D01*
G01X309248Y613708D02*
X310898D01*
G01X300007Y615008D02*
X325537D01*
G01X300546Y613708D02*
X306198D01*
G01X300007Y615008D02*
X325537D01*
G01X299379Y612541D02*
X300546Y613708D01*
G01X290624Y605625D02*
X300007Y615008D01*
G01X297223Y610385D02*
X298213D01*
G01X290624Y605625D02*
X300007Y615008D01*
G01X296056Y609218D02*
X297223Y610385D01*
G01X290624Y605625D02*
X300007Y615008D01*
G01X293900Y607062D02*
X294890D01*
G01X290624Y605625D02*
X300007Y615008D01*
G01X291163Y604325D02*
X293900Y607062D01*
G01X290624Y605625D02*
X300007Y615008D01*
G01X343867Y614588D02*
X342775D01*
G01X344406Y615888D02*
X342674D01*
G01X344766Y613689D02*
X343867Y614588D01*
G01X346066Y614228D02*
X344406Y615888D01*
G01X344766Y606998D02*
Y613689D01*
G01X346066Y600873D02*
Y614228D01*
G01X344766Y601412D02*
Y603948D01*
G01X346066Y600873D02*
Y614228D01*
G01X341988Y598634D02*
X344766Y601412D01*
G01X342527Y597334D02*
X346066Y600873D01*
G01X340338Y598634D02*
X341988D01*
G01X342527Y597334D02*
X346066Y600873D01*
G01X329686Y597334D02*
X342527D01*
G01X335638Y598634D02*
X337288D01*
G01X329686Y597334D02*
X342527D01*
G01X330225Y598634D02*
X332588D01*
G01X329686Y597334D02*
X342527D01*
G01X327300Y601559D02*
X330225Y598634D01*
G01X326000Y601020D02*
X329686Y597334D01*
G01X327300Y605939D02*
Y601559D01*
G01X326000Y605400D02*
Y601020D01*
G01X323681Y609558D02*
X327300Y605939D01*
G01X323142Y608258D02*
X326000Y605400D01*
G01X320792Y609558D02*
X323681D01*
G01X301944Y608258D02*
X323142D01*
G01X316092Y609558D02*
X317742D01*
G01X301944Y608258D02*
X323142D01*
G01X311392Y609558D02*
X313042D01*
G01X301944Y608258D02*
X323142D01*
G01X306692Y609558D02*
X308342D01*
G01X301944Y608258D02*
X323142D01*
G01X301405Y609558D02*
X303642D01*
G01X301944Y608258D02*
X323142D01*
G01X293441Y601594D02*
X301405Y609558D01*
G01X293980Y600294D02*
X301944Y608258D01*
G01X344406Y615888D02*
X342674D01*
G01X343867Y614588D02*
X342775D01*
G01X346066Y614228D02*
X344406Y615888D01*
G01X344766Y613689D02*
X343867Y614588D01*
G01X346066Y600873D02*
Y614228D01*
G01X344766Y606998D02*
Y613689D01*
G01Y601412D02*
Y603948D01*
G01X342527Y597334D02*
X346066Y600873D01*
G01X341988Y598634D02*
X344766Y601412D01*
G01X340338Y598634D02*
X341988D01*
G01X329686Y597334D02*
X342527D01*
G01X340338Y598634D02*
X341988D01*
G01X335638D02*
X337288D01*
G01X330225D02*
X332588D01*
G01X326000Y601020D02*
X329686Y597334D01*
G01X327300Y601559D02*
X330225Y598634D01*
G01X326000Y605400D02*
Y601020D01*
G01X327300Y605939D02*
Y601559D01*
G01X323142Y608258D02*
X326000Y605400D01*
G01X323681Y609558D02*
X327300Y605939D01*
G01X301944Y608258D02*
X323142D01*
G01X320792Y609558D02*
X323681D01*
G01X316092D02*
X317742D01*
G01X311392D02*
X313042D01*
G01X306692D02*
X308342D01*
G01X301405D02*
X303642D01*
G01X293980Y600294D02*
X301944Y608258D01*
G01X293441Y601594D02*
X301405Y609558D01*
G01X405013Y130608D02*
X385974Y157900D01*
G01X405934Y131560D02*
X387196Y158422D01*
G01X416886Y122897D02*
X405013Y130608D01*
G01X417393Y124119D02*
X405934Y131560D01*
G01X421572Y121900D02*
X416886Y122897D01*
G01X421709Y123200D02*
X417393Y124119D01*
G01X422567Y123200D02*
X421709D01*
G01X423106Y121900D02*
X421572D01*
G01X422567Y123200D02*
X421709D01*
G01X425846Y124640D02*
X423106Y121900D01*
G01X424546Y125179D02*
X422567Y123200D01*
G01X425846Y141400D02*
Y124640D01*
G01X424546Y141400D02*
Y125179D01*
G01X405934Y131560D02*
X387196Y158422D01*
G01X405013Y130608D02*
X385974Y157900D01*
G01X417393Y124119D02*
X405934Y131560D01*
G01X416886Y122897D02*
X405013Y130608D01*
G01X421709Y123200D02*
X417393Y124119D01*
G01X421572Y121900D02*
X416886Y122897D01*
G01X422567Y123200D02*
X421709D01*
G01X421572Y121900D02*
X416886Y122897D01*
G01X423106Y121900D02*
X421572D01*
G01X424546Y125179D02*
X422567Y123200D01*
G01X425846Y124640D02*
X423106Y121900D01*
G01X424546Y141400D02*
Y125179D01*
G01X425846Y141400D02*
Y124640D01*
G01X402039Y127054D02*
X381998Y156029D01*
G01X402962Y128005D02*
X383221Y156547D01*
G01X415000Y118638D02*
X402039Y127054D01*
G01X415507Y119860D02*
X402962Y128005D01*
G01X422022Y117140D02*
X415000Y118638D01*
G01X422293Y118412D02*
X415507Y119860D01*
G01X422155Y117112D02*
X422022Y117140D01*
G01X422293Y118412D02*
X415507Y119860D01*
G01X429673Y118412D02*
X422293D01*
G01X430212Y117112D02*
X422155D01*
G01X429673Y118412D02*
X422293D01*
G01X402962Y128005D02*
X383221Y156547D01*
G01X402039Y127054D02*
X381998Y156029D01*
G01X415507Y119860D02*
X402962Y128005D01*
G01X415000Y118638D02*
X402039Y127054D01*
G01X422293Y118412D02*
X415507Y119860D01*
G01X422022Y117140D02*
X415000Y118638D01*
G01X422155Y117112D02*
X422022Y117140D01*
G01X429673Y118412D02*
X422293D01*
G01X422155Y117112D02*
X422022Y117140D01*
G01X430212Y117112D02*
X422155D01*
G01X397983Y123774D02*
X378430Y153112D01*
G01X398917Y124719D02*
X379655Y153619D01*
G01X410953Y115353D02*
X397983Y123774D01*
G01X411662Y116443D02*
X398917Y124719D01*
G01X410952Y115353D02*
X410953D01*
G01X411662Y116443D02*
X398917Y124719D01*
G01X411162Y115217D02*
X410952Y115353D01*
G01X411662Y116443D02*
X398917Y124719D01*
G01X418944Y113650D02*
X411162Y115217D01*
G01X419074Y114950D02*
X411662Y116443D01*
G01X433650Y113650D02*
X418944D01*
G01X433111Y114950D02*
X419074D01*
G01X398917Y124719D02*
X379655Y153619D01*
G01X397983Y123774D02*
X378430Y153112D01*
G01X411662Y116443D02*
X398917Y124719D01*
G01X410953Y115353D02*
X397983Y123774D01*
G01X410952Y115353D02*
X410953D01*
G01X411162Y115217D02*
X410952Y115353D01*
G01X419074Y114950D02*
X411662Y116443D01*
G01X418944Y113650D02*
X411162Y115217D01*
G01X433111Y114950D02*
X419074D01*
G01X433650Y113650D02*
X418944D01*
G01X395483Y119529D02*
X374689Y150723D01*
G01X396417Y120474D02*
X375914Y151230D01*
G01X408091Y111342D02*
X395483Y119529D01*
G01X408594Y112566D02*
X396417Y120474D01*
G01X419052Y109075D02*
X408091Y111342D01*
G01X419186Y110375D02*
X408594Y112566D01*
G01X436414Y109075D02*
X419052D01*
G01X435875Y110375D02*
X419186D01*
G01X396417Y120474D02*
X375914Y151230D01*
G01X395483Y119529D02*
X374689Y150723D01*
G01X408594Y112566D02*
X396417Y120474D01*
G01X408091Y111342D02*
X395483Y119529D01*
G01X419186Y110375D02*
X408594Y112566D01*
G01X419052Y109075D02*
X408091Y111342D01*
G01X435875Y110375D02*
X419186D01*
G01X436414Y109075D02*
X419052D01*
G01X392147Y116927D02*
X371605Y147748D01*
G01X393081Y117872D02*
X372830Y148255D01*
G01X408935Y106025D02*
X392147Y116927D01*
G01X409321Y107325D02*
X393081Y117872D01*
G01X441964Y106025D02*
X408935D01*
G01X441425Y107325D02*
X409321D01*
G01X393081Y117872D02*
X372830Y148255D01*
G01X392147Y116927D02*
X371605Y147748D01*
G01X409321Y107325D02*
X393081Y117872D01*
G01X408935Y106025D02*
X392147Y116927D01*
G01X441425Y107325D02*
X409321D01*
G01X441964Y106025D02*
X408935D01*
G01X390660Y114244D02*
X367645Y148671D01*
G01X389728Y113299D02*
X366425Y148156D01*
G01X406136Y104200D02*
X390660Y114244D01*
G01X405751Y102900D02*
X389728Y113299D01*
G01X446400Y104200D02*
X406136D01*
G01X446939Y102900D02*
X405751D01*
G01X389728Y113299D02*
X366425Y148156D01*
G01X390660Y114244D02*
X367645Y148671D01*
G01X405751Y102900D02*
X389728Y113299D01*
G01X406136Y104200D02*
X390660Y114244D01*
G01X446939Y102900D02*
X405751D01*
G01X446400Y104200D02*
X406136D01*
G01X386682Y111283D02*
X362135Y147875D01*
G01X387614Y112229D02*
X363355Y148391D01*
G01X404361Y99803D02*
X386682Y111283D01*
G01X404747Y101103D02*
X387614Y112229D01*
G01X448342Y99803D02*
X404361D01*
G01X447803Y101103D02*
X404747D01*
G01X387614Y112229D02*
X363355Y148391D01*
G01X386682Y111283D02*
X362135Y147875D01*
G01X404747Y101103D02*
X387614Y112229D01*
G01X404361Y99803D02*
X386682Y111283D01*
G01X447803Y101103D02*
X404747D01*
G01X448342Y99803D02*
X404361D01*
G01X384701Y182989D02*
X389728Y206646D01*
G01X386029Y182981D02*
X391057Y206644D01*
G01X389396Y159523D02*
X384701Y182989D01*
G01X390621Y160030D02*
X386029Y182981D01*
G01X395072Y150987D02*
X389396Y159523D01*
G01X396011Y151924D02*
X390621Y160030D01*
G01X401065Y146988D02*
X395072Y150987D01*
G01X401459Y148288D02*
X396011Y151924D01*
G01X421047Y146988D02*
X401065D01*
G01X421047Y148288D02*
X401459D01*
G01X386029Y182981D02*
X391057Y206644D01*
G01X384701Y182989D02*
X389728Y206646D01*
G01X390621Y160030D02*
X386029Y182981D01*
G01X389396Y159523D02*
X384701Y182989D01*
G01X396011Y151924D02*
X390621Y160030D01*
G01X395072Y150987D02*
X389396Y159523D01*
G01X401459Y148288D02*
X396011Y151924D01*
G01X401065Y146988D02*
X395072Y150987D01*
G01X421047Y148288D02*
X401459D01*
G01X421047Y146988D02*
X401065D01*
G01X380773Y183886D02*
X385781Y207444D01*
G01X382101Y183878D02*
X387110Y207442D01*
G01X385974Y157900D02*
X380773Y183886D01*
G01X387196Y158422D02*
X382101Y183878D01*
G01X426710Y142264D02*
G03X425846Y141400I0J-864D01*
G01X426710Y143564D02*
G03X424546Y141400I0J-2164D01*
G01X428134Y142264D02*
X426710D01*
G01X428134Y143564D02*
X426710D01*
G01X382101Y183878D02*
X387110Y207442D01*
G01X380773Y183886D02*
X385781Y207444D01*
G01X387196Y158422D02*
X382101Y183878D01*
G01X385974Y157900D02*
X380773Y183886D01*
G01X426710Y143564D02*
G03X424546Y141400I0J-2164D01*
G01X426710Y142264D02*
G03X425846Y141400I0J-864D01*
G01X428134Y143564D02*
X426710D01*
G01X428134Y142264D02*
X426710D01*
G01X376536Y183453D02*
X381462Y206627D01*
G01X377864Y183444D02*
X382791Y206624D01*
G01X381998Y156029D02*
X376536Y183453D01*
G01X383221Y156547D02*
X377864Y183444D01*
G01D02*
X382791Y206624D01*
G01X376536Y183453D02*
X381462Y206627D01*
G01X383221Y156547D02*
X377864Y183444D01*
G01X381998Y156029D02*
X376536Y183453D01*
G01X372332Y183616D02*
X377458Y207731D01*
G01X373660Y183608D02*
X378788Y207731D01*
G01X378430Y153112D02*
X372332Y183616D01*
G01X379655Y153619D02*
X373660Y183608D01*
G01D02*
X378788Y207731D01*
G01X372332Y183616D02*
X377458Y207731D01*
G01X379655Y153619D02*
X373660Y183608D01*
G01X378430Y153112D02*
X372332Y183616D01*
G01X368334Y202780D02*
X371309Y216773D01*
G01X369664Y202780D02*
X372637Y216768D01*
G01X369407Y197733D02*
X368334Y202780D01*
G01X370737Y197733D02*
X369664Y202780D01*
G01X367286Y187753D02*
X369407Y197733D01*
G01X368614Y187745D02*
X370737Y197733D01*
G01X374689Y150723D02*
X367286Y187753D01*
G01X375914Y151230D02*
X368614Y187745D01*
G01X369664Y202780D02*
X372637Y216768D01*
G01X368334Y202780D02*
X371309Y216773D01*
G01X370737Y197733D02*
X369664Y202780D01*
G01X369407Y197733D02*
X368334Y202780D01*
G01X368614Y187745D02*
X370737Y197733D01*
G01X367286Y187753D02*
X369407Y197733D01*
G01X375914Y151230D02*
X368614Y187745D01*
G01X374689Y150723D02*
X367286Y187753D01*
G01X361331Y199105D02*
X365190Y217260D01*
G01X362659Y199097D02*
X366519Y217255D01*
G01X371605Y147748D02*
X361331Y199105D01*
G01X372830Y148255D02*
X362659Y199097D01*
G01D02*
X366519Y217255D01*
G01X361331Y199105D02*
X365190Y217260D01*
G01X372830Y148255D02*
X362659Y199097D01*
G01X371605Y147748D02*
X361331Y199105D01*
G01X356178Y202606D02*
X360945Y225039D01*
G01X357936Y194335D02*
X356178Y202606D01*
G01X367645Y148671D02*
X357936Y194335D01*
G01X366425Y148156D02*
X356664Y194065D01*
G01X356178Y202606D02*
X360945Y225039D01*
G01X357936Y194335D02*
X356178Y202606D01*
G01X366425Y148156D02*
X356664Y194065D01*
G01X367645Y148671D02*
X357936Y194335D01*
G01X362135Y147875D02*
X359667Y159483D01*
G01X363355Y148391D02*
X360889Y159989D01*
G01X363355Y148391D02*
X360889Y159989D01*
G01X362135Y147875D02*
X359667Y159483D01*
G01X389728Y206646D02*
X359639Y349861D01*
G01X391057Y206644D02*
X360832Y350507D01*
G01X391057Y206644D02*
X360832Y350507D01*
G01X389728Y206646D02*
X359639Y349861D01*
G01X385781Y207444D02*
X357450Y342911D01*
G01X387110Y207442D02*
X358644Y343556D01*
G01X387110Y207442D02*
X358644Y343556D01*
G01X385781Y207444D02*
X357450Y342911D01*
G01X381462Y206627D02*
X356397Y327204D01*
G01X382791Y206624D02*
X357591Y327849D01*
G01X382791Y206624D02*
X357591Y327849D01*
G01X381462Y206627D02*
X356397Y327204D01*
G01X372637Y216768D02*
X356838Y294139D01*
G01X372637Y216768D02*
X356838Y294139D01*
G01X432934Y119834D02*
X430212Y117112D01*
G01X431634Y120373D02*
X429673Y118412D01*
G01X432934Y146072D02*
Y119834D01*
G01X431634Y146072D02*
Y120373D01*
G01D02*
X429673Y118412D01*
G01X432934Y119834D02*
X430212Y117112D01*
G01X431634Y146072D02*
Y120373D01*
G01X432934Y146072D02*
Y119834D01*
G01X440020Y120020D02*
X433650Y113650D01*
G01X438720Y120559D02*
X433111Y114950D01*
G01X440020Y141401D02*
Y120020D01*
G01X438720Y141401D02*
Y120559D01*
G01D02*
X433111Y114950D01*
G01X440020Y120020D02*
X433650Y113650D01*
G01X438720Y141401D02*
Y120559D01*
G01X440020Y141401D02*
Y120020D01*
G01X447107Y119768D02*
X436414Y109075D01*
G01X445807Y120307D02*
X435875Y110375D01*
G01X447107Y146072D02*
Y119768D01*
G01X445807Y146072D02*
Y120307D01*
G01D02*
X435875Y110375D01*
G01X447107Y119768D02*
X436414Y109075D01*
G01X445807Y146072D02*
Y120307D01*
G01X447107Y146072D02*
Y119768D01*
G01X454193Y118254D02*
X441964Y106025D01*
G01X452893Y118793D02*
X441425Y107325D01*
G01X454193Y141401D02*
Y118254D01*
G01X452893Y141401D02*
Y118793D01*
G01D02*
X441425Y107325D01*
G01X454193Y118254D02*
X441964Y106025D01*
G01X452893Y141401D02*
Y118793D01*
G01X454193Y141401D02*
Y118254D01*
G01X454200Y112000D02*
X446400Y104200D01*
G01X454739Y110700D02*
X446939Y102900D01*
G01X457561Y112000D02*
X454200D01*
G01X458100Y110700D02*
X454739D01*
G01X459980Y114419D02*
X457561Y112000D01*
G01X461280Y113880D02*
X458100Y110700D01*
G01X459980Y146072D02*
Y114419D01*
G01X461280Y146072D02*
Y113880D01*
G01X454739Y110700D02*
X446939Y102900D01*
G01X454200Y112000D02*
X446400Y104200D01*
G01X458100Y110700D02*
X454739D01*
G01X457561Y112000D02*
X454200D01*
G01X461280Y113880D02*
X458100Y110700D01*
G01X459980Y114419D02*
X457561Y112000D01*
G01X461280Y146072D02*
Y113880D01*
G01X459980Y146072D02*
Y114419D01*
G01X455639Y107100D02*
X448342Y99803D01*
G01X455100Y108400D02*
X447803Y101103D01*
G01X461300Y107100D02*
X455639D01*
G01X460761Y108400D02*
X455100D01*
G01X468367Y114167D02*
X461300Y107100D01*
G01X467067Y114706D02*
X460761Y108400D01*
G01X468367Y141401D02*
Y114167D01*
G01X467067Y141401D02*
Y114706D01*
G01X455100Y108400D02*
X447803Y101103D01*
G01X455639Y107100D02*
X448342Y99803D01*
G01X460761Y108400D02*
X455100D01*
G01X461300Y107100D02*
X455639D01*
G01X467067Y114706D02*
X460761Y108400D01*
G01X468367Y114167D02*
X461300Y107100D01*
G01X467067Y141401D02*
Y114706D01*
G01X468367Y141401D02*
Y114167D01*
G01X433850Y146988D02*
G03X432934Y146072I0J-916D01*
G01X433850Y148288D02*
G03X431634Y146072I0J-2216D01*
G01X435221Y146988D02*
X433850D01*
G01X435221Y148288D02*
X433850D01*
G01D02*
G03X431634Y146072I0J-2216D01*
G01X433850Y146988D02*
G03X432934Y146072I0J-916D01*
G01X435221Y148288D02*
X433850D01*
G01X435221Y146988D02*
X433850D01*
G01X440883Y142264D02*
G03X440020Y141401I0J-863D01*
G01X440883Y143564D02*
G03X438720Y141401I0J-2163D01*
G01X442307Y142264D02*
X440883D01*
G01X442307Y143564D02*
X440883D01*
G01D02*
G03X438720Y141401I0J-2163D01*
G01X440883Y142264D02*
G03X440020Y141401I0J-863D01*
G01X442307Y143564D02*
X440883D01*
G01X442307Y142264D02*
X440883D01*
G01X448023Y146988D02*
G03X447107Y146072I0J-916D01*
G01X448023Y148288D02*
G03X445807Y146072I0J-2216D01*
G01X449394Y146988D02*
X448023D01*
G01X449394Y148288D02*
X448023D01*
G01D02*
G03X445807Y146072I0J-2216D01*
G01X448023Y146988D02*
G03X447107Y146072I0J-916D01*
G01X449394Y148288D02*
X448023D01*
G01X449394Y146988D02*
X448023D01*
G01X455056Y142264D02*
G03X454193Y141401I0J-863D01*
G01X455056Y143564D02*
G03X452893Y141401I0J-2163D01*
G01X456480Y142264D02*
X455056D01*
G01X456480Y143564D02*
X455056D01*
G01D02*
G03X452893Y141401I0J-2163D01*
G01X455056Y142264D02*
G03X454193Y141401I0J-863D01*
G01X456480Y143564D02*
X455056D01*
G01X456480Y142264D02*
X455056D01*
G01X462196Y148288D02*
G03X459980Y146072I0J-2216D01*
G01X462196Y146988D02*
G03X461280Y146072I0J-916D01*
G01X463567Y148288D02*
X462196D01*
G01X463567Y146988D02*
X462196D01*
G01D02*
G03X461280Y146072I0J-916D01*
G01X462196Y148288D02*
G03X459980Y146072I0J-2216D01*
G01X463567Y146988D02*
X462196D01*
G01X463567Y148288D02*
X462196D01*
G01X469230Y142264D02*
G03X468367Y141401I0J-863D01*
G01X469230Y143564D02*
G03X467067Y141401I0J-2163D01*
G01X470654Y142264D02*
X469230D01*
G01X470654Y143564D02*
X469230D01*
G01D02*
G03X467067Y141401I0J-2163D01*
G01X469230Y142264D02*
G03X468367Y141401I0J-863D01*
G01X470654Y143564D02*
X469230D01*
G01X470654Y142264D02*
X469230D01*
G01X546319Y119981D02*
Y146072D01*
G01X545019Y119442D02*
Y146072D01*
G01X552053Y114247D02*
X546319Y119981D01*
G01X551514Y112947D02*
X545019Y119442D01*
G01X558849Y114247D02*
X552053D01*
G01X558978Y112947D02*
X551514D01*
G01X563103Y115098D02*
X558849Y114247D01*
G01X563610Y113873D02*
X558978Y112947D01*
G01X574534Y122720D02*
X563103Y115098D01*
G01X575479Y121786D02*
X563610Y113873D01*
G01X545019Y119442D02*
Y146072D01*
G01X546319Y119981D02*
Y146072D01*
G01X551514Y112947D02*
X545019Y119442D01*
G01X552053Y114247D02*
X546319Y119981D01*
G01X558978Y112947D02*
X551514D01*
G01X558849Y114247D02*
X552053D01*
G01X563610Y113873D02*
X558978Y112947D01*
G01X563103Y115098D02*
X558849Y114247D01*
G01X575479Y121786D02*
X563610Y113873D01*
G01X574534Y122720D02*
X563103Y115098D01*
G01X553406Y120194D02*
Y141401D01*
G01X552106Y119655D02*
Y141401D01*
G01X555000Y118600D02*
X553406Y120194D01*
G01X554461Y117300D02*
X552106Y119655D01*
G01X556367Y118600D02*
X555000D01*
G01X556496Y117300D02*
X554461D01*
G01X559603Y119247D02*
X556367Y118600D01*
G01X560110Y118022D02*
X556496Y117300D01*
G01X567765Y124688D02*
X559603Y119247D01*
G01X568590Y123674D02*
X560110Y118022D01*
G01X570116Y127039D02*
X567765Y124688D01*
G01X571132Y126216D02*
X568590Y123674D01*
G01X572756Y131106D02*
X570116Y127039D01*
G01X585744Y148724D02*
X571132Y126216D01*
G01X585744Y148724D02*
X571132Y126216D01*
G01X585744Y148724D02*
X571132Y126216D01*
G01X585744Y148724D02*
X571132Y126216D01*
G01X552106Y119655D02*
Y141401D01*
G01X553406Y120194D02*
Y141401D01*
G01X554461Y117300D02*
X552106Y119655D01*
G01X555000Y118600D02*
X553406Y120194D01*
G01X556496Y117300D02*
X554461D01*
G01X556367Y118600D02*
X555000D01*
G01X560110Y118022D02*
X556496Y117300D01*
G01X559603Y119247D02*
X556367Y118600D01*
G01X568590Y123674D02*
X560110Y118022D01*
G01X567765Y124688D02*
X559603Y119247D01*
G01X571132Y126216D02*
X568590Y123674D01*
G01X570116Y127039D02*
X567765Y124688D01*
G01X585744Y148724D02*
X571132Y126216D01*
G01X572756Y131106D02*
X570116Y127039D01*
G01X503800Y120963D02*
Y146072D01*
G01X502500Y120424D02*
Y146072D01*
G01X539363Y85400D02*
X503800Y120963D01*
G01X538824Y84100D02*
X502500Y120424D01*
G01X571298Y85400D02*
X539363D01*
G01X571436Y84100D02*
X538824D01*
G01X502500Y120424D02*
Y146072D01*
G01X503800Y120963D02*
Y146072D01*
G01X538824Y84100D02*
X502500Y120424D01*
G01X539363Y85400D02*
X503800Y120963D01*
G01X571436Y84100D02*
X538824D01*
G01X571298Y85400D02*
X539363D01*
G01X510886Y119167D02*
Y141401D01*
G01X509586Y118628D02*
Y141401D01*
G01X539653Y90400D02*
X510886Y119167D01*
G01X539114Y89100D02*
X509586Y118628D01*
G01X568283Y90400D02*
X539653D01*
G01X568423Y89100D02*
X539114D01*
G01X581557Y93279D02*
X568283Y90400D01*
G01X582066Y92058D02*
X568423Y89100D01*
G01X509586Y118628D02*
Y141401D01*
G01X510886Y119167D02*
Y141401D01*
G01X539114Y89100D02*
X509586Y118628D01*
G01X539653Y90400D02*
X510886Y119167D01*
G01X568423Y89100D02*
X539114D01*
G01X568283Y90400D02*
X539653D01*
G01X582066Y92058D02*
X568423Y89100D01*
G01X581557Y93279D02*
X568283Y90400D01*
G01X517973Y117527D02*
Y146072D01*
G01X516673Y116988D02*
Y146072D01*
G01X539318Y96182D02*
X517973Y117527D01*
G01X538779Y94882D02*
X516673Y116988D01*
G01X567483Y96182D02*
X539318D01*
G01X567612Y94882D02*
X538779D01*
G01X578792Y98445D02*
X567483Y96182D01*
G01X579293Y97219D02*
X567612Y94882D01*
G01X516673Y116988D02*
Y146072D01*
G01X517973Y117527D02*
Y146072D01*
G01X538779Y94882D02*
X516673Y116988D01*
G01X539318Y96182D02*
X517973Y117527D01*
G01X567612Y94882D02*
X538779D01*
G01X567483Y96182D02*
X539318D01*
G01X579293Y97219D02*
X567612Y94882D01*
G01X578792Y98445D02*
X567483Y96182D01*
G01X525060Y116979D02*
Y141401D01*
G01X523760Y116440D02*
Y141401D01*
G01X541906Y100133D02*
X525060Y116979D01*
G01X541367Y98833D02*
X523760Y116440D01*
G01X564029Y100133D02*
X541906D01*
G01X564158Y98833D02*
X541367D01*
G01X573248Y101975D02*
X564029Y100133D01*
G01X573750Y100749D02*
X564158Y98833D01*
G01X523760Y116440D02*
Y141401D01*
G01X525060Y116979D02*
Y141401D01*
G01X541367Y98833D02*
X523760Y116440D01*
G01X541906Y100133D02*
X525060Y116979D01*
G01X564158Y98833D02*
X541367D01*
G01X564029Y100133D02*
X541906D01*
G01X573750Y100749D02*
X564158Y98833D01*
G01X573248Y101975D02*
X564029Y100133D01*
G01X532146Y116354D02*
Y146072D01*
G01X530846Y115815D02*
Y146072D01*
G01X544597Y103903D02*
X532146Y116354D01*
G01X544058Y102603D02*
X530846Y115815D01*
G01X560216Y103903D02*
X544597D01*
G01X560345Y102603D02*
X544058D01*
G01X569508Y105761D02*
X560216Y103903D01*
G01X570010Y104535D02*
X560345Y102603D01*
G01X586955Y117178D02*
X569508Y105761D01*
G01X587896Y116240D02*
X570010Y104535D01*
G01X530846Y115815D02*
Y146072D01*
G01X532146Y116354D02*
Y146072D01*
G01X544058Y102603D02*
X530846Y115815D01*
G01X544597Y103903D02*
X532146Y116354D01*
G01X560345Y102603D02*
X544058D01*
G01X560216Y103903D02*
X544597D01*
G01X570010Y104535D02*
X560345Y102603D01*
G01X569508Y105761D02*
X560216Y103903D01*
G01X587896Y116240D02*
X570010Y104535D01*
G01X586955Y117178D02*
X569508Y105761D01*
G01X539233Y120153D02*
Y141401D01*
G01X537933Y119614D02*
Y141401D01*
G01X550986Y108400D02*
X539233Y120153D01*
G01X550447Y107100D02*
X537933Y119614D01*
G01X559060Y108400D02*
X550986D01*
G01X559189Y107100D02*
X550447D01*
G01X565597Y109708D02*
X559060Y108400D01*
G01X566100Y108482D02*
X559189Y107100D01*
G01X579941Y119135D02*
X565597Y109708D01*
G01X580883Y118198D02*
X566100Y108482D01*
G01X537933Y119614D02*
Y141401D01*
G01X539233Y120153D02*
Y141401D01*
G01X550447Y107100D02*
X537933Y119614D01*
G01X550986Y108400D02*
X539233Y120153D01*
G01X559189Y107100D02*
X550447D01*
G01X559060Y108400D02*
X550986D01*
G01X566100Y108482D02*
X559189Y107100D01*
G01X565597Y109708D02*
X559060Y108400D01*
G01X580883Y118198D02*
X566100Y108482D01*
G01X579941Y119135D02*
X565597Y109708D01*
G01X571169Y80734D02*
X578516Y82297D01*
G01X571169Y80734D02*
X578516Y82297D01*
G01X537229Y80734D02*
X571169D01*
G01X536843Y79434D02*
X571306D01*
G01X537229Y80734D02*
X571169D01*
G01X511035Y96196D02*
X536843Y79434D01*
G01X511858Y97212D02*
X537229Y80734D01*
G01X507911Y99320D02*
X511035Y96196D01*
G01X508831Y100240D02*
X511858Y97212D01*
G01X507230Y100965D02*
G03X507911Y99320I2327J0D01*
G01X508530Y100966D02*
G03X508831Y100240I1027J0D01*
G01X507230Y102070D02*
Y100965D01*
G01X508530Y102070D02*
Y100966D01*
G01X571169Y80734D02*
X578516Y82297D01*
G01X537229Y80734D02*
X571169D01*
G01X536843Y79434D02*
X571306D01*
G01X511858Y97212D02*
X537229Y80734D01*
G01X511035Y96196D02*
X536843Y79434D01*
G01X508831Y100240D02*
X511858Y97212D01*
G01X507911Y99320D02*
X511035Y96196D01*
G01X508530Y100966D02*
G03X508831Y100240I1027J0D01*
G01X507230Y100965D02*
G03X507911Y99320I2327J0D01*
G01X508530Y102070D02*
Y100966D01*
G01X507230Y102070D02*
Y100965D01*
G01X561451Y170610D02*
X556905D01*
G01X561178Y171910D02*
X556905D01*
G01X570370Y174515D02*
X561451Y170610D01*
G01X569577Y175588D02*
X561178Y171910D01*
G01X588151Y195165D02*
X570370Y174515D01*
G01X586948Y195761D02*
X569577Y175588D01*
G01X561178Y171910D02*
X556905D01*
G01X561451Y170610D02*
X556905D01*
G01X569577Y175588D02*
X561178Y171910D01*
G01X570370Y174515D02*
X561451Y170610D01*
G01X586948Y195761D02*
X569577Y175588D01*
G01X588151Y195165D02*
X570370Y174515D01*
G01X547235Y146988D02*
X548606D01*
G01X547235Y148288D02*
X548606D01*
G01X546319Y146072D02*
G02X547235Y146988I916J0D01*
G01X545019Y146072D02*
G02X547235Y148288I2216J0D01*
G01D02*
X548606D01*
G01X547235Y146988D02*
X548606D01*
G01X545019Y146072D02*
G02X547235Y148288I2216J0D01*
G01X546319Y146072D02*
G02X547235Y146988I916J0D01*
G01X554269Y142264D02*
X555693D01*
G01X554269Y143564D02*
X555693D01*
G01X553406Y141401D02*
G02X554269Y142264I863J0D01*
G01X552106Y141401D02*
G02X554269Y143564I2163J0D01*
G01D02*
X555693D01*
G01X554269Y142264D02*
X555693D01*
G01X552106Y141401D02*
G02X554269Y143564I2163J0D01*
G01X553406Y141401D02*
G02X554269Y142264I863J0D01*
G01X504716Y146988D02*
X506087D01*
G01X504716Y148288D02*
X506087D01*
G01X503800Y146072D02*
G02X504716Y146988I916J0D01*
G01X502500Y146072D02*
G02X504716Y148288I2216J0D01*
G01D02*
X506087D01*
G01X504716Y146988D02*
X506087D01*
G01X502500Y146072D02*
G02X504716Y148288I2216J0D01*
G01X503800Y146072D02*
G02X504716Y146988I916J0D01*
G01X511749Y142264D02*
X513173D01*
G01X511749Y143564D02*
X513173D01*
G01X510886Y141401D02*
G02X511749Y142264I863J0D01*
G01X509586Y141401D02*
G02X511749Y143564I2163J0D01*
G01D02*
X513173D01*
G01X511749Y142264D02*
X513173D01*
G01X509586Y141401D02*
G02X511749Y143564I2163J0D01*
G01X510886Y141401D02*
G02X511749Y142264I863J0D01*
G01X518889Y146988D02*
X520260D01*
G01X518889Y148288D02*
X520260D01*
G01X517973Y146072D02*
G02X518889Y146988I916J0D01*
G01X516673Y146072D02*
G02X518889Y148288I2216J0D01*
G01D02*
X520260D01*
G01X518889Y146988D02*
X520260D01*
G01X516673Y146072D02*
G02X518889Y148288I2216J0D01*
G01X517973Y146072D02*
G02X518889Y146988I916J0D01*
G01X525923Y142264D02*
X527347D01*
G01X525923Y143564D02*
X527347D01*
G01X525060Y141401D02*
G02X525923Y142264I863J0D01*
G01X523760Y141401D02*
G02X525923Y143564I2163J0D01*
G01D02*
X527347D01*
G01X525923Y142264D02*
X527347D01*
G01X523760Y141401D02*
G02X525923Y143564I2163J0D01*
G01X525060Y141401D02*
G02X525923Y142264I863J0D01*
G01X533062Y146988D02*
X534433D01*
G01X533062Y148288D02*
X534433D01*
G01X532146Y146072D02*
G02X533062Y146988I916J0D01*
G01X530846Y146072D02*
G02X533062Y148288I2216J0D01*
G01D02*
X534433D01*
G01X533062Y146988D02*
X534433D01*
G01X530846Y146072D02*
G02X533062Y148288I2216J0D01*
G01X532146Y146072D02*
G02X533062Y146988I916J0D01*
G01X540096Y142264D02*
X541520D01*
G01X540096Y143564D02*
X541520D01*
G01X539233Y141401D02*
G02X540096Y142264I863J0D01*
G01X537933Y141401D02*
G02X540096Y143564I2163J0D01*
G01D02*
X541520D01*
G01X540096Y142264D02*
X541520D01*
G01X537933Y141401D02*
G02X540096Y143564I2163J0D01*
G01X539233Y141401D02*
G02X540096Y142264I863J0D01*
G01X579977Y131102D02*
X574534Y122720D01*
G01X592322Y147723D02*
X575479Y121786D01*
G01X582537Y135044D02*
X581638Y133660D01*
G01X592322Y147723D02*
X575479Y121786D01*
G01X592322Y147723D02*
X575479Y121786D01*
G01X592322Y147723D02*
X575479Y121786D01*
G01X592322Y147723D02*
X575479Y121786D01*
G01X579977Y131102D02*
X574534Y122720D01*
G01X582537Y135044D02*
X581638Y133660D01*
G01X575315Y135048D02*
X574417Y133664D01*
G01X575315Y135048D02*
X574417Y133664D01*
G01X584134Y88144D02*
X571298Y85400D01*
G01X584641Y86922D02*
X571436Y84100D01*
G01X609023Y104310D02*
X584134Y88144D01*
G01X609963Y103370D02*
X584641Y86922D01*
G01X613534Y111256D02*
X609023Y104310D01*
G01X628338Y131665D02*
X609963Y103370D01*
G01X616093Y115198D02*
X615195Y113814D01*
G01X628338Y131665D02*
X609963Y103370D01*
G01X618653Y119140D02*
X617755Y117756D01*
G01X628338Y131665D02*
X609963Y103370D01*
G01X627116Y132171D02*
X620314Y121698D01*
G01X628338Y131665D02*
X609963Y103370D01*
G01X665274Y311659D02*
X627116Y132171D01*
G01X666604Y311659D02*
X628338Y131665D01*
G01X584641Y86922D02*
X571436Y84100D01*
G01X584134Y88144D02*
X571298Y85400D01*
G01X609963Y103370D02*
X584641Y86922D01*
G01X609023Y104310D02*
X584134Y88144D01*
G01X628338Y131665D02*
X609963Y103370D01*
G01X613534Y111256D02*
X609023Y104310D01*
G01X616093Y115198D02*
X615195Y113814D01*
G01X618653Y119140D02*
X617755Y117756D01*
G01X627116Y132171D02*
X620314Y121698D01*
G01X666604Y311659D02*
X628338Y131665D01*
G01X665274Y311659D02*
X627116Y132171D01*
G01X603167Y107312D02*
X581557Y93279D01*
G01X604107Y106372D02*
X582066Y92058D01*
G01X606937Y113118D02*
X603167Y107312D01*
G01X622799Y135158D02*
X604107Y106372D01*
G01X609497Y117060D02*
X608598Y115676D01*
G01X622799Y135158D02*
X604107Y106372D01*
G01X612056Y121002D02*
X611158Y119618D01*
G01X622799Y135158D02*
X604107Y106372D01*
G01X614616Y124944D02*
X613717Y123560D01*
G01X622799Y135158D02*
X604107Y106372D01*
G01X621577Y135664D02*
X616277Y127502D01*
G01X622799Y135158D02*
X604107Y106372D01*
G01D02*
X582066Y92058D01*
G01X603167Y107312D02*
X581557Y93279D01*
G01X622799Y135158D02*
X604107Y106372D01*
G01X606937Y113118D02*
X603167Y107312D01*
G01X609497Y117060D02*
X608598Y115676D01*
G01X612056Y121002D02*
X611158Y119618D01*
G01X614616Y124944D02*
X613717Y123560D01*
G01X621577Y135664D02*
X616277Y127502D01*
G01X597317Y110546D02*
X578792Y98445D01*
G01X598258Y109607D02*
X579293Y97219D01*
G01X601944Y117671D02*
X597317Y110546D01*
G01X617377Y139048D02*
X598258Y109607D01*
G01X604504Y121613D02*
X603605Y120229D01*
G01X617377Y139048D02*
X598258Y109607D01*
G01X607064Y125555D02*
X606165Y124171D01*
G01X617377Y139048D02*
X598258Y109607D01*
G01X616155Y139554D02*
X608725Y128113D01*
G01X617377Y139048D02*
X598258Y109607D01*
G01D02*
X579293Y97219D01*
G01X597317Y110546D02*
X578792Y98445D01*
G01X617377Y139048D02*
X598258Y109607D01*
G01X601944Y117671D02*
X597317Y110546D01*
G01X604504Y121613D02*
X603605Y120229D01*
G01X607064Y125555D02*
X606165Y124171D01*
G01X616155Y139554D02*
X608725Y128113D01*
G01X591580Y113983D02*
X573248Y101975D01*
G01X592521Y113045D02*
X573750Y100749D01*
G01X599387Y126005D02*
X591580Y113983D01*
G01X611177Y141772D02*
X592521Y113045D01*
G01X601947Y129947D02*
X601048Y128563D01*
G01X611177Y141772D02*
X592521Y113045D01*
G01X604507Y133889D02*
X603608Y132505D01*
G01X611177Y141772D02*
X592521Y113045D01*
G01X611177Y141772D02*
X592521Y113045D01*
G01D02*
X573750Y100749D01*
G01X591580Y113983D02*
X573248Y101975D01*
G01X611177Y141772D02*
X592521Y113045D01*
G01X599387Y126005D02*
X591580Y113983D01*
G01X601947Y129947D02*
X601048Y128563D01*
G01X604507Y133889D02*
X603608Y132505D01*
G01X593298Y126945D02*
X586955Y117178D01*
G01X603742Y140639D02*
X587896Y116240D01*
G01X595858Y130887D02*
X594959Y129503D01*
G01X603742Y140639D02*
X587896Y116240D01*
G01X598418Y134829D02*
X597519Y133445D01*
G01X603742Y140639D02*
X587896Y116240D01*
G01X603742Y140639D02*
X587896Y116240D01*
G01X603742Y140639D02*
X587896Y116240D01*
G01X593298Y126945D02*
X586955Y117178D01*
G01X595858Y130887D02*
X594959Y129503D01*
G01X598418Y134829D02*
X597519Y133445D01*
G01X582626Y123270D02*
X579941Y119135D01*
G01X597545Y143854D02*
X580883Y118198D01*
G01X585186Y127211D02*
X584287Y125828D01*
G01X597545Y143854D02*
X580883Y118198D01*
G01X587746Y131153D02*
X586847Y129769D01*
G01X597545Y143854D02*
X580883Y118198D01*
G01X596323Y144360D02*
X589407Y133711D01*
G01X597545Y143854D02*
X580883Y118198D01*
G01X597545Y143854D02*
X580883Y118198D01*
G01X582626Y123270D02*
X579941Y119135D01*
G01X585186Y127211D02*
X584287Y125828D01*
G01X587746Y131153D02*
X586847Y129769D01*
G01X596323Y144360D02*
X589407Y133711D01*
G01X632947Y130649D02*
X672158Y315140D01*
G01X631725Y131155D02*
X670828Y315140D01*
G01X612998Y99932D02*
X632947Y130649D01*
G01X612058Y100872D02*
X631725Y131155D01*
G01X586367Y82636D02*
X612998Y99932D01*
G01X585861Y83858D02*
X612058Y100872D01*
G01X571439Y79462D02*
X586367Y82636D01*
G01X578516Y82297D02*
X585861Y83858D01*
G01X571306Y79434D02*
X571439Y79462D01*
G01X631725Y131155D02*
X670828Y315140D01*
G01X632947Y130649D02*
X672158Y315140D01*
G01X612058Y100872D02*
X631725Y131155D01*
G01X612998Y99932D02*
X632947Y130649D01*
G01X585861Y83858D02*
X612058Y100872D01*
G01X586367Y82636D02*
X612998Y99932D01*
G01X578516Y82297D02*
X585861Y83858D01*
G01X571439Y79462D02*
X586367Y82636D01*
G01X571439Y79462D02*
X586367Y82636D01*
G01X571306Y79434D02*
X571439Y79462D01*
G01X571306Y79434D02*
X571439Y79462D01*
G01X611159Y303399D02*
X588151Y195165D01*
G01X609829Y303399D02*
X586948Y195761D01*
G01X609829Y303399D02*
X586948Y195761D01*
G01X611159Y303399D02*
X588151Y195165D01*
G01X585097Y138986D02*
X584198Y137602D01*
G01X591100Y148229D02*
X586758Y141543D01*
G01X624105Y303521D02*
X591100Y148229D01*
G01X625435Y303521D02*
X592322Y147723D01*
G01X585097Y138986D02*
X584198Y137602D01*
G01X591100Y148229D02*
X586758Y141543D01*
G01X625435Y303521D02*
X592322Y147723D01*
G01X624105Y303521D02*
X591100Y148229D01*
G01X577874Y138990D02*
X576976Y137606D01*
G01X584522Y149230D02*
X579535Y141548D01*
G01X617173Y302842D02*
X584522Y149230D01*
G01X618503Y302842D02*
X585744Y148724D01*
G01X577874Y138990D02*
X576976Y137606D01*
G01X584522Y149230D02*
X579535Y141548D01*
G01X618503Y302842D02*
X585744Y148724D01*
G01X617173Y302842D02*
X584522Y149230D01*
G01X658662Y310169D02*
X621577Y135664D01*
G01X659992Y310169D02*
X622799Y135158D01*
G01X659992Y310169D02*
X622799Y135158D01*
G01X658662Y310169D02*
X621577Y135664D01*
G01X651977Y308083D02*
X616155Y139554D01*
G01X653307Y308083D02*
X617377Y139048D01*
G01X653307Y308083D02*
X617377Y139048D01*
G01X651977Y308083D02*
X616155Y139554D01*
G01X609955Y142278D02*
X606168Y136447D01*
G01X644766Y306045D02*
X609955Y142278D01*
G01X611227Y142007D02*
X611177Y141772D01*
G01X646096Y306045D02*
X611227Y142007D01*
G01X609955Y142278D02*
X606168Y136447D01*
G01X611227Y142007D02*
X611177Y141772D01*
G01X644766Y306045D02*
X609955Y142278D01*
G01X646096Y306045D02*
X611227Y142007D01*
G01X644766Y306045D02*
X609955Y142278D01*
G01X602520Y141145D02*
X600079Y137387D01*
G01X637669Y306817D02*
X602520Y141145D01*
G01X638999Y306817D02*
X603742Y140639D01*
G01X602520Y141145D02*
X600079Y137387D01*
G01X638999Y306817D02*
X603742Y140639D01*
G01X637669Y306817D02*
X602520Y141145D01*
G01X630687Y306021D02*
X596323Y144360D01*
G01X632017Y306021D02*
X597545Y143854D01*
G01X632017Y306021D02*
X597545Y143854D01*
G01X630687Y306021D02*
X596323Y144360D01*
G01X605556Y329753D02*
X611159Y303399D01*
G01X607085Y316306D02*
X609829Y303399D01*
G01X604226Y329753D02*
X607085Y316306D01*
G01X625293Y422596D02*
X605556Y329753D01*
G01X623963Y422596D02*
X604226Y329753D01*
G01X607085Y316306D02*
X609829Y303399D01*
G01X605556Y329753D02*
X611159Y303399D01*
G01X604226Y329753D02*
X607085Y316306D01*
G01X605556Y329753D02*
X611159Y303399D01*
G01X623963Y422596D02*
X604226Y329753D01*
G01X625293Y422596D02*
X605556Y329753D01*
G01X618335Y330677D02*
X624105Y303521D01*
G01X619665Y330677D02*
X625435Y303521D01*
G01X636279Y415112D02*
X618335Y330677D01*
G01X637606Y415102D02*
X619665Y330677D01*
G01D02*
X625435Y303521D01*
G01X618335Y330677D02*
X624105Y303521D01*
G01X637606Y415102D02*
X619665Y330677D01*
G01X636279Y415112D02*
X618335Y330677D01*
G01X611811Y328077D02*
X617173Y302842D01*
G01X613141Y328077D02*
X618503Y302842D01*
G01X630801Y417414D02*
X611811Y328077D01*
G01X632128Y417404D02*
X613141Y328077D01*
G01D02*
X618503Y302842D01*
G01X611811Y328077D02*
X617173Y302842D01*
G01X632128Y417404D02*
X613141Y328077D01*
G01X630801Y417414D02*
X611811Y328077D01*
G01X638809Y334069D02*
X644766Y306045D01*
G01X640139Y334069D02*
X646096Y306045D01*
G01X653927Y405201D02*
X638809Y334069D01*
G01X655254Y405189D02*
X640139Y334069D01*
G01D02*
X646096Y306045D01*
G01X638809Y334069D02*
X644766Y306045D01*
G01X655254Y405189D02*
X640139Y334069D01*
G01X653927Y405201D02*
X638809Y334069D01*
G01X632016Y333412D02*
X637669Y306817D01*
G01X633346Y333412D02*
X638999Y306817D01*
G01X647970Y408524D02*
X632016Y333412D01*
G01X649298Y408514D02*
X633346Y333412D01*
G01D02*
X638999Y306817D01*
G01X632016Y333412D02*
X637669Y306817D01*
G01X649298Y408514D02*
X633346Y333412D01*
G01X647970Y408524D02*
X632016Y333412D01*
G01X625085Y332376D02*
X630687Y306021D01*
G01X626415Y332376D02*
X632017Y306021D01*
G01X632569Y367582D02*
X625085Y332376D01*
G01X631366Y355666D02*
X626415Y332376D01*
G01D02*
X632017Y306021D01*
G01X625085Y332376D02*
X630687Y306021D01*
G01X631366Y355666D02*
X626415Y332376D01*
G01X632569Y367582D02*
X625085Y332376D01*
G01X616139Y517602D02*
X636279Y415112D01*
G01X617464Y517603D02*
X637606Y415102D01*
G01X617464Y517603D02*
X637606Y415102D01*
G01X616139Y517602D02*
X636279Y415112D01*
G01X611360Y516326D02*
X630801Y417414D01*
G01X612685Y516327D02*
X632128Y417404D01*
G01X612685Y516327D02*
X632128Y417404D01*
G01X611360Y516326D02*
X630801Y417414D01*
G01X635046Y379228D02*
X632569Y367582D01*
G01X636318Y378958D02*
X631366Y355666D01*
G01X641991Y411900D02*
X635046Y379228D01*
G01X643318Y411890D02*
X636318Y378958D01*
G01X620809Y519576D02*
X641991Y411900D01*
G01X622134Y519578D02*
X643318Y411890D01*
G01X636318Y378958D02*
X631366Y355666D01*
G01X635046Y379228D02*
X632569Y367582D01*
G01X643318Y411890D02*
X636318Y378958D01*
G01X641991Y411900D02*
X635046Y379228D01*
G01X622134Y519578D02*
X643318Y411890D01*
G01X620809Y519576D02*
X641991Y411900D01*
G01X615278Y469703D02*
X625293Y422596D01*
G01X618984Y446015D02*
X623963Y422596D01*
G01X614006Y469433D02*
X618984Y446016D01*
G01X606021Y513246D02*
X615278Y469703D01*
G01X609377Y491205D02*
X614006Y469433D01*
G01X604691Y513246D02*
X609377Y491205D01*
G01X618984Y446015D02*
X623963Y422596D01*
G01X615278Y469703D02*
X625293Y422596D01*
G01X614006Y469433D02*
X618984Y446016D01*
G01X615278Y469703D02*
X625293Y422596D01*
G01X609377Y491205D02*
X614006Y469433D01*
G01X606021Y513246D02*
X615278Y469703D01*
G01X604691Y513246D02*
X609377Y491205D01*
G01X606021Y513246D02*
X615278Y469703D01*
G01X634950Y521831D02*
X659600Y401516D01*
G01X636276Y521837D02*
X660929Y401511D01*
G01X636276Y521837D02*
X660929Y401511D01*
G01X634950Y521831D02*
X659600Y401516D01*
G01X630758Y524393D02*
X653927Y405201D01*
G01X632083Y524393D02*
X655254Y405189D01*
G01X632083Y524393D02*
X655254Y405189D01*
G01X630758Y524393D02*
X653927Y405201D01*
G01X625742Y521183D02*
X647970Y408524D01*
G01X627067Y521185D02*
X649298Y408514D01*
G01X627067Y521185D02*
X649298Y408514D01*
G01X625742Y521183D02*
X647970Y408524D01*
G01X613838Y550020D02*
X606021Y513246D01*
G01X608658Y531904D02*
X604691Y513246D01*
G01X612616Y550526D02*
X608658Y531904D01*
G01X622841Y563883D02*
X613838Y550020D01*
G01X621901Y564823D02*
X612616Y550526D01*
G01X638712Y574189D02*
X622841Y563883D01*
G01X638206Y575411D02*
X621901Y564823D01*
G01X608658Y531904D02*
X604691Y513246D01*
G01X613838Y550020D02*
X606021Y513246D01*
G01X612616Y550526D02*
X608658Y531904D01*
G01X613838Y550020D02*
X606021Y513246D01*
G01X621901Y564823D02*
X612616Y550526D01*
G01X622841Y563883D02*
X613838Y550020D01*
G01X638206Y575411D02*
X621901Y564823D01*
G01X638712Y574189D02*
X622841Y563883D01*
G01X621900Y547235D02*
X616139Y517602D01*
G01X623126Y546727D02*
X617464Y517603D01*
G01X628502Y557024D02*
X621900Y547235D01*
G01X629439Y556087D02*
X623126Y546727D01*
G01X643322Y567020D02*
X628502Y557024D01*
G01X643837Y565799D02*
X629439Y556087D01*
G01X623126Y546727D02*
X617464Y517603D01*
G01X621900Y547235D02*
X616139Y517602D01*
G01X629439Y556087D02*
X623126Y546727D01*
G01X628502Y557024D02*
X621900Y547235D01*
G01X643837Y565799D02*
X629439Y556087D01*
G01X643322Y567020D02*
X628502Y557024D01*
G01X617697Y548931D02*
X611360Y516326D01*
G01X618923Y548423D02*
X612685Y516327D01*
G01X625265Y560150D02*
X617697Y548931D01*
G01X626202Y559213D02*
X618923Y548423D01*
G01X641056Y570801D02*
X625265Y560150D01*
G01X641564Y569575D02*
X626202Y559213D01*
G01X618923Y548423D02*
X612685Y516327D01*
G01X617697Y548931D02*
X611360Y516326D01*
G01X626202Y559213D02*
X618923Y548423D01*
G01X625265Y560150D02*
X617697Y548931D01*
G01X641564Y569575D02*
X626202Y559213D01*
G01X641056Y570801D02*
X625265Y560150D01*
G01X639697Y523268D02*
X665502Y397923D01*
G01X641023Y523275D02*
X666831Y397919D01*
G01X642248Y536390D02*
X639697Y523268D01*
G01X643474Y535882D02*
X641023Y523275D01*
G01X647364Y543975D02*
X642248Y536390D01*
G01X641023Y523275D02*
X666831Y397919D01*
G01X639697Y523268D02*
X665502Y397923D01*
G01X643474Y535882D02*
X641023Y523275D01*
G01X642248Y536390D02*
X639697Y523268D01*
G01X647364Y543975D02*
X642248Y536390D01*
G01X638215Y538579D02*
X634950Y521831D01*
G01X639441Y538071D02*
X636276Y521837D01*
G01X643659Y546652D02*
X638215Y538579D01*
G01X644596Y545715D02*
X639441Y538071D01*
G01D02*
X636276Y521837D01*
G01X638215Y538579D02*
X634950Y521831D01*
G01X644596Y545715D02*
X639441Y538071D01*
G01X643659Y546652D02*
X638215Y538579D01*
G01X634030Y541225D02*
X630758Y524393D01*
G01X635256Y540717D02*
X632083Y524393D01*
G01X639697Y549628D02*
X634030Y541225D01*
G01X640634Y548691D02*
X635256Y540717D01*
G01X651110Y557326D02*
X639697Y549628D01*
G01X651625Y556105D02*
X640634Y548691D01*
G01X635256Y540717D02*
X632083Y524393D01*
G01X634030Y541225D02*
X630758Y524393D01*
G01X640634Y548691D02*
X635256Y540717D01*
G01X639697Y549628D02*
X634030Y541225D01*
G01X651625Y556105D02*
X640634Y548691D01*
G01X651110Y557326D02*
X639697Y549628D01*
G01X629987Y543020D02*
X625742Y521183D01*
G01X631213Y542512D02*
X627067Y521185D01*
G01X636120Y552113D02*
X629987Y543020D01*
G01X637057Y551176D02*
X631213Y542512D01*
G01X648941Y560760D02*
X636120Y552113D01*
G01X649668Y559682D02*
X637057Y551176D01*
G01X649668Y559682D02*
X637057Y551176D01*
G01X649668Y559682D02*
X637057Y551176D01*
G01X631213Y542512D02*
X627067Y521185D01*
G01X629987Y543020D02*
X625742Y521183D01*
G01X637057Y551176D02*
X631213Y542512D01*
G01X636120Y552113D02*
X629987Y543020D01*
G01X649668Y559682D02*
X637057Y551176D01*
G01X648941Y560760D02*
X636120Y552113D01*
G01X625744Y544975D02*
X620809Y519576D01*
G01X626970Y544467D02*
X622134Y519578D01*
G01X629165Y550047D02*
X625744Y544975D01*
G01X630243Y549320D02*
X626970Y544467D01*
G01X632581Y555111D02*
X629165Y550047D01*
G01X633518Y554174D02*
X630243Y549320D01*
G01X646314Y564374D02*
X632581Y555111D01*
G01X646829Y563153D02*
X633518Y554174D01*
G01X626970Y544467D02*
X622134Y519578D01*
G01X625744Y544975D02*
X620809Y519576D01*
G01X630243Y549320D02*
X626970Y544467D01*
G01X629165Y550047D02*
X625744Y544975D01*
G01X633518Y554174D02*
X630243Y549320D01*
G01X632581Y555111D02*
X629165Y550047D01*
G01X646829Y563153D02*
X633518Y554174D01*
G01X646314Y564374D02*
X632581Y555111D01*
G01X704608Y588196D02*
X638712Y574189D01*
G01X704608Y589526D02*
X638206Y575411D01*
G01X704608Y589526D02*
X638206Y575411D01*
G01X704608Y588196D02*
X638712Y574189D01*
G01X698819Y582031D02*
X641056Y570801D01*
G01X698819Y580706D02*
X641564Y569575D01*
G01X698819Y580706D02*
X641564Y569575D01*
G01X698819Y582031D02*
X641056Y570801D01*
G01X659310Y339717D02*
X665274Y311659D01*
G01X660640Y339717D02*
X666604Y311659D01*
G01X671174Y395532D02*
X659310Y339717D01*
G01X672504Y395532D02*
X660640Y339717D01*
G01D02*
X666604Y311659D01*
G01X659310Y339717D02*
X665274Y311659D01*
G01X672504Y395532D02*
X660640Y339717D01*
G01X671174Y395532D02*
X659310Y339717D01*
G01X652756Y337951D02*
X658662Y310169D01*
G01X654086Y337951D02*
X659992Y310169D01*
G01X665502Y397923D02*
X652756Y337951D01*
G01X666831Y397919D02*
X654086Y337951D01*
G01D02*
X659992Y310169D01*
G01X652756Y337951D02*
X658662Y310169D01*
G01X666831Y397919D02*
X654086Y337951D01*
G01X665502Y397923D02*
X652756Y337951D01*
G01X645860Y336873D02*
X651977Y308083D01*
G01X647190Y336873D02*
X653307Y308083D01*
G01X659600Y401516D02*
X645860Y336873D01*
G01X660929Y401511D02*
X647190Y336873D01*
G01D02*
X653307Y308083D01*
G01X645860Y336873D02*
X651977Y308083D01*
G01X660929Y401511D02*
X647190Y336873D01*
G01X659600Y401516D02*
X645860Y336873D01*
G01X666251Y342934D02*
X677480Y395765D01*
G01X664921Y342934D02*
X676150Y395765D01*
G01X672158Y315140D02*
X666251Y342934D01*
G01X670828Y315140D02*
X664921Y342934D01*
G01D02*
X676150Y395765D01*
G01X666251Y342934D02*
X677480Y395765D01*
G01X670828Y315140D02*
X664921Y342934D01*
G01X672158Y315140D02*
X666251Y342934D01*
G01X644143Y522657D02*
X671174Y395532D01*
G01X645470Y522669D02*
X672504Y395532D01*
G01X645470Y522669D02*
X672504Y395532D01*
G01X644143Y522657D02*
X671174Y395532D01*
G01X677480Y395765D02*
X663242Y462757D01*
G01X676150Y395765D02*
X661912Y462757D01*
G01X676150Y395765D02*
X661912Y462757D01*
G01X677480Y395765D02*
X663242Y462757D01*
G01X667377Y491842D02*
X669524Y501941D01*
G01X666047Y491842D02*
X668302Y502447D01*
G01X668401Y487028D02*
X667377Y491842D01*
G01X667071Y487028D02*
X666047Y491842D01*
G01X663242Y462757D02*
X668401Y487028D01*
G01X661912Y462757D02*
X667071Y487028D01*
G01X666047Y491842D02*
X668302Y502447D01*
G01X667377Y491842D02*
X669524Y501941D01*
G01X667071Y487028D02*
X666047Y491842D01*
G01X668401Y487028D02*
X667377Y491842D01*
G01X661912Y462757D02*
X667071Y487028D01*
G01X663242Y462757D02*
X668401Y487028D01*
G01X646545Y535026D02*
X644143Y522657D01*
G01X647746Y534387D02*
X645470Y522669D01*
G01X653559Y542039D02*
X646664Y535145D01*
G01X654479Y541119D02*
X647746Y534387D01*
G01X658274Y542039D02*
G03X653559I-2358J-2358D01*
G01X657354Y541119D02*
G03X654479I-1438J-1437D01*
G01X659192Y541121D02*
X658274Y542039D01*
G01Y540199D02*
X657354Y541119D01*
G01X647746Y534387D02*
X645470Y522669D01*
G01X646545Y535026D02*
X644143Y522657D01*
G01X654479Y541119D02*
X647746Y534387D01*
G01X653559Y542039D02*
X646664Y535145D01*
G01X657354Y541119D02*
G03X654479I-1438J-1437D01*
G01X658274Y542039D02*
G03X653559I-2358J-2358D01*
G01X658274Y540199D02*
X657354Y541119D01*
G01X659192Y541121D02*
X658274Y542039D01*
G01X648301Y543038D02*
X643474Y535882D01*
G01X657469Y550791D02*
X647364Y543975D01*
G01X658197Y549713D02*
X648301Y543038D01*
G01X657689Y550939D02*
X657469Y550791D01*
G01X658197Y549713D02*
X648301Y543038D01*
G01X674589Y552901D02*
X658197Y549713D01*
G01X657948Y550990D02*
X657689Y550939D01*
G01X674589Y552901D02*
X658197Y549713D01*
G01X674589Y554226D02*
X657948Y550989D01*
G01X674589Y552901D02*
X658197Y549713D01*
G01X678191Y553524D02*
X674589Y554226D01*
G01X676500Y552529D02*
X674589Y552901D01*
G01X677819Y552272D02*
X676500Y552529D01*
G01X680688Y549994D02*
G03X678282Y553487I-3739J0D01*
G01X679388Y549994D02*
G03X677819Y552272I-2438J0D01*
G01X680688Y548873D02*
Y549994D01*
G01X679388Y548873D02*
Y549994D01*
G01X680742Y548568D02*
G02X680688Y548873I834J305D01*
G01X679520Y548121D02*
G02X679388Y548873I2057J749D01*
G01X681351Y547614D02*
G02X680742Y548568I1854J1855D01*
G01X680431Y546694D02*
G02X679520Y548121I2774J2775D01*
G01X681916Y547049D02*
X681351Y547614D01*
G01X681014Y546111D02*
X680431Y546694D01*
G01X683540Y546418D02*
G02X681916Y547049I0J2405D01*
G01X683540Y545118D02*
G02X681014Y546111I-1J3706D01*
G01X685182Y545977D02*
G03X683540Y546418I-1641J-2834D01*
G01X684530Y544852D02*
G03X683540Y545118I-990J-1709D01*
G01X686089Y545133D02*
X685427Y545795D01*
G01X685171Y544211D02*
X684530Y544852D01*
G01X648301Y543038D02*
X643474Y535882D01*
G01X658197Y549713D02*
X648301Y543038D01*
G01X657469Y550791D02*
X647364Y543975D01*
G01X657689Y550939D02*
X657469Y550791D01*
G01X674589Y552901D02*
X658197Y549713D01*
G01X657689Y550939D02*
X657469Y550791D01*
G01X657948Y550990D02*
X657689Y550939D01*
G01X674589Y554226D02*
X657948Y550989D01*
G01X676500Y552529D02*
X674589Y552901D01*
G01X678191Y553524D02*
X674589Y554226D01*
G01X677819Y552272D02*
X676500Y552529D01*
G01X678191Y553524D02*
X674589Y554226D01*
G01X679388Y549994D02*
G03X677819Y552272I-2438J0D01*
G01X680688Y549994D02*
G03X678282Y553487I-3739J0D01*
G01X679388Y548873D02*
Y549994D01*
G01X680688Y548873D02*
Y549994D01*
G01X679520Y548121D02*
G02X679388Y548873I2057J749D01*
G01X680742Y548568D02*
G02X680688Y548873I834J305D01*
G01X680431Y546694D02*
G02X679520Y548121I2774J2775D01*
G01X681351Y547614D02*
G02X680742Y548568I1854J1855D01*
G01X681014Y546111D02*
X680431Y546694D01*
G01X681916Y547049D02*
X681351Y547614D01*
G01X683540Y545118D02*
G02X681014Y546111I-1J3706D01*
G01X683540Y546418D02*
G02X681916Y547049I0J2405D01*
G01X684530Y544852D02*
G03X683540Y545118I-990J-1709D01*
G01X685182Y545977D02*
G03X683540Y546418I-1641J-2834D01*
G01X685171Y544211D02*
X684530Y544852D01*
G01X686089Y545133D02*
X685427Y545795D01*
G01X654567Y554011D02*
X643659Y546652D01*
G01X655078Y552786D02*
X644596Y545715D01*
G01X691809Y561429D02*
X654567Y554011D01*
G01X673444Y556445D02*
X655078Y552786D01*
G01X682627Y558274D02*
X673444Y556445D01*
G01X691812Y560104D02*
X682627Y558274D01*
G01X693123Y559849D02*
X691812Y560104D01*
G01X693558Y561089D02*
X691809Y561429D01*
G01X693123Y559849D02*
X691812Y560104D01*
G01X695598Y560020D02*
X693558Y561089D01*
G01X694703Y559020D02*
X693123Y559849D01*
G01X699101Y554822D02*
X695598Y560020D01*
G01X698093Y553991D02*
X694703Y559020D01*
G01X700724Y553199D02*
X699101Y554822D01*
G01X699804Y552279D02*
X698093Y553991D01*
G01X655078Y552786D02*
X644596Y545715D01*
G01X654567Y554011D02*
X643659Y546652D01*
G01X673444Y556445D02*
X655078Y552786D01*
G01X691809Y561429D02*
X654567Y554011D01*
G01X682627Y558274D02*
X673444Y556445D01*
G01X691809Y561429D02*
X654567Y554011D01*
G01X691812Y560104D02*
X682627Y558274D01*
G01X691809Y561429D02*
X654567Y554011D01*
G01X693123Y559849D02*
X691812Y560104D01*
G01X691809Y561429D02*
X654567Y554011D01*
G01X693558Y561089D02*
X691809Y561429D01*
G01X694703Y559020D02*
X693123Y559849D01*
G01X695598Y560020D02*
X693558Y561089D01*
G01X698093Y553991D02*
X694703Y559020D01*
G01X699101Y554822D02*
X695598Y560020D01*
G01X699804Y552279D02*
X698093Y553991D01*
G01X700724Y553199D02*
X699101Y554822D01*
G01X693201Y566090D02*
X651110Y557326D01*
G01X693206Y564763D02*
X651625Y556105D01*
G01X714106Y561908D02*
X693201Y566090D01*
G01X713599Y560683D02*
X693206Y564763D01*
G01X717058Y559941D02*
X714106Y561908D01*
G01X716119Y559003D02*
X713599Y560683D01*
G01X693206Y564763D02*
X651625Y556105D01*
G01X693201Y566090D02*
X651110Y557326D01*
G01X713599Y560683D02*
X693206Y564763D01*
G01X714106Y561908D02*
X693201Y566090D01*
G01X716119Y559003D02*
X713599Y560683D01*
G01X717058Y559941D02*
X714106Y561908D01*
G01X648940Y560760D02*
X648941D01*
G01X649153Y560903D02*
X648940Y560760D01*
G01X696809Y570837D02*
X649153Y560903D01*
G01X696814Y569510D02*
X649668Y559682D01*
G01X648940Y560760D02*
X648941D01*
G01X649153Y560903D02*
X648940Y560760D01*
G01X696814Y569510D02*
X649668Y559682D01*
G01X696809Y570837D02*
X649153Y560903D01*
G01X697565Y575034D02*
X646314Y564374D01*
G01X697574Y573707D02*
X646829Y563153D01*
G01X697574Y573707D02*
X646829Y563153D01*
G01X697565Y575034D02*
X646314Y564374D01*
G01X713489Y515933D02*
X720071Y517332D01*
G01X713489Y517263D02*
X719424Y518524D01*
G01X705793Y517568D02*
X713489Y515933D01*
G01X705793Y518898D02*
X713489Y517263D01*
G01X698162Y515947D02*
X705793Y517568D01*
G01X698418Y517331D02*
X705793Y518898D01*
G01X677293Y511515D02*
X698162Y515947D01*
G01X693821Y516355D02*
X695435Y516698D01*
G01X689224Y515378D02*
X690838Y515721D01*
G01X684627Y514402D02*
X686241Y514745D01*
G01X676787Y512737D02*
X681644Y513769D01*
G01X674611Y509773D02*
X677293Y511514D01*
G01X673671Y510713D02*
X676787Y512737D01*
G01X669524Y501941D02*
X674611Y509773D01*
G01X668302Y502447D02*
X673671Y510713D01*
G01X713489Y517263D02*
X719424Y518524D01*
G01X713489Y515933D02*
X720071Y517332D01*
G01X705793Y518898D02*
X713489Y517263D01*
G01X705793Y517568D02*
X713489Y515933D01*
G01X698418Y517331D02*
X705793Y518898D01*
G01X698162Y515947D02*
X705793Y517568D01*
G01X693821Y516355D02*
X695435Y516698D01*
G01X677293Y511515D02*
X698162Y515947D01*
G01X689224Y515378D02*
X690838Y515721D01*
G01X677293Y511515D02*
X698162Y515947D01*
G01X684627Y514402D02*
X686241Y514745D01*
G01X677293Y511515D02*
X698162Y515947D01*
G01X676787Y512737D02*
X681644Y513769D01*
G01X677293Y511515D02*
X698162Y515947D01*
G01X673671Y510713D02*
X676787Y512737D01*
G01X674611Y509773D02*
X677293Y511514D01*
G01X668302Y502447D02*
X673671Y510713D01*
G01X669524Y501941D02*
X674611Y509773D01*
G01X742003Y580248D02*
X704608Y588196D01*
G01X754450Y578933D02*
X704608Y589526D01*
G01X754450Y578933D02*
X704608Y589526D01*
G01X754450Y578933D02*
X704608Y589526D01*
G01X754450Y578933D02*
X704608Y589526D01*
G01X742003Y580248D02*
X704608Y588196D01*
G01X643572Y567072D02*
X643322Y567020D01*
G01X699329Y577321D02*
X643837Y565799D01*
G01X643573Y567072D02*
X643572D01*
G01X699329Y577321D02*
X643837Y565799D01*
G01X699324Y578648D02*
X643573Y567072D01*
G01X699329Y577321D02*
X643837Y565799D01*
G01X758985Y566718D02*
X699324Y578648D01*
G01X758981Y565392D02*
X699329Y577321D01*
G01D02*
X643837Y565799D01*
G01X643572Y567072D02*
X643322Y567020D01*
G01X643573Y567072D02*
X643572D01*
G01X699324Y578648D02*
X643573Y567072D01*
G01X758981Y565392D02*
X699329Y577321D01*
G01X758985Y566718D02*
X699324Y578648D01*
G01X757966Y570534D02*
X698819Y582031D01*
G01X757966Y569209D02*
X698819Y580706D01*
G01X757966Y569209D02*
X698819Y580706D01*
G01X757966Y570534D02*
X698819Y582031D01*
G01X742258Y561750D02*
X696809Y570837D01*
G01X741751Y560525D02*
X696814Y569510D01*
G01X741751Y560525D02*
X696814Y569510D01*
G01X742258Y561750D02*
X696809Y570837D01*
G01X761442Y562615D02*
X697565Y575034D01*
G01X761442Y561290D02*
X697574Y573707D01*
G01X761442Y561290D02*
X697574Y573707D01*
G01X761442Y562615D02*
X697565Y575034D01*
G01X770796Y567687D02*
X758981Y565392D01*
G01X794265Y563121D02*
X770796Y567687D01*
G01D02*
X758981Y565392D01*
G01X794265Y563121D02*
X770796Y567687D01*
G01X717960Y558585D02*
X717058Y559941D01*
G01X716660Y558192D02*
X716119Y559003D01*
G01X717960Y553595D02*
Y558585D01*
G01X716660Y553594D02*
Y558192D01*
G01X718298Y552779D02*
G02X717960Y553595I816J816D01*
G01X717378Y551860D02*
G02X716660Y553594I1736J1735D01*
G01X719100Y551977D02*
X718298Y552779D01*
G01X718182Y551055D02*
X717378Y551859D01*
G01X716660Y558192D02*
X716119Y559003D01*
G01X717960Y558585D02*
X717058Y559941D01*
G01X716660Y553594D02*
Y558192D01*
G01X717960Y553595D02*
Y558585D01*
G01X717378Y551860D02*
G02X716660Y553594I1736J1735D01*
G01X718298Y552779D02*
G02X717960Y553595I816J816D01*
G01X718182Y551055D02*
X717378Y551859D01*
G01X719100Y551977D02*
X718298Y552779D01*
G01X753985Y553933D02*
X742258Y561750D01*
G01X753156Y552922D02*
X741751Y560525D01*
G01X757534Y550384D02*
X753985Y553933D01*
G01X756616Y549462D02*
X753156Y552922D01*
G01D02*
X741751Y560525D01*
G01X753985Y553933D02*
X742258Y561750D01*
G01X756616Y549462D02*
X753156Y552922D01*
G01X757534Y550384D02*
X753985Y553933D01*
G01X767091Y563714D02*
X761442Y562615D01*
G01X767091Y562389D02*
X761442Y561290D01*
G01X776133Y561948D02*
X767091Y563714D01*
G01X775494Y560748D02*
X767091Y562389D01*
G01X777199Y560882D02*
X776133Y561948D01*
G01X776281Y559961D02*
X775494Y560748D01*
G01X777944Y560139D02*
X777199Y560882D01*
G01X776281Y559961D02*
X775494Y560748D01*
G01X777025Y559219D02*
X776281Y559961D01*
G01X778730Y558240D02*
G03X777944Y560139I-2685J1D01*
G01X777429Y558240D02*
G03X777025Y559219I-1385J1D01*
G01X778730Y557653D02*
Y558240D01*
G01X777430Y557652D02*
Y558241D01*
G01X779059Y556859D02*
G02X778730Y557653I794J794D01*
G01X778139Y555939D02*
G02X777430Y557652I1715J1713D01*
G01X780034Y555884D02*
X779059Y556859D01*
G01X779116Y554963D02*
X778139Y555939D01*
G01X767091Y562389D02*
X761442Y561290D01*
G01X767091Y563714D02*
X761442Y562615D01*
G01X775494Y560748D02*
X767091Y562389D01*
G01X776133Y561948D02*
X767091Y563714D01*
G01X776281Y559961D02*
X775494Y560748D01*
G01X777199Y560882D02*
X776133Y561948D01*
G01X777944Y560139D02*
X777199Y560882D01*
G01X777025Y559219D02*
X776281Y559961D01*
G01X777944Y560139D02*
X777199Y560882D01*
G01X777429Y558240D02*
G03X777025Y559219I-1385J1D01*
G01X778730Y558240D02*
G03X777944Y560139I-2685J1D01*
G01X777430Y557652D02*
Y558241D01*
G01X778730Y557653D02*
Y558240D01*
G01X778139Y555939D02*
G02X777430Y557652I1715J1713D01*
G01X779059Y556859D02*
G02X778730Y557653I794J794D01*
G01X779116Y554963D02*
X778139Y555939D01*
G01X780034Y555884D02*
X779059Y556859D01*
G01X722938Y522918D02*
Y522921D01*
G01X721637Y520737D02*
Y522918D01*
G01X722937Y520198D02*
Y522918D01*
G01X721637Y520737D02*
Y522918D01*
G01X720071Y517332D02*
X722937Y520198D01*
G01X719424Y518524D02*
X721637Y520737D01*
G01D02*
Y522918D01*
G01X722938D02*
Y522921D01*
G01X722937Y520198D02*
Y522918D01*
G01X719424Y518524D02*
X721637Y520737D01*
G01X720071Y517332D02*
X722937Y520198D01*
G01X746600Y579271D02*
X744986Y579614D01*
G01X751197Y578294D02*
X749583Y578637D01*
G01X755794Y577317D02*
X754180Y577660D01*
G01X755794Y578647D02*
X754450Y578932D01*
G01X773493Y581079D02*
X755794Y577317D01*
G01X773493Y582409D02*
X755794Y578647D01*
G01X804474Y574492D02*
X773493Y581079D01*
G01X824460Y571574D02*
X773493Y582409D01*
G01X824460Y571574D02*
X773493Y582409D01*
G01X824460Y571574D02*
X773493Y582409D01*
G01X824460Y571574D02*
X773493Y582409D01*
G01X824460Y571574D02*
X773493Y582409D01*
G01X746600Y579271D02*
X744986Y579614D01*
G01X751197Y578294D02*
X749583Y578637D01*
G01X755794Y578647D02*
X754450Y578932D01*
G01X755794Y577317D02*
X754180Y577660D01*
G01X773493Y582409D02*
X755794Y578647D01*
G01X773493Y581079D02*
X755794Y577317D01*
G01X824460Y571574D02*
X773493Y582409D01*
G01X804474Y574492D02*
X773493Y581079D01*
G01X770796Y569012D02*
X758985Y566718D01*
G01X794903Y564322D02*
X770796Y569012D01*
G01D02*
X758985Y566718D01*
G01X794903Y564322D02*
X770796Y569012D01*
G01X774324Y573714D02*
X757966Y570534D01*
G01X774320Y572388D02*
X757966Y569209D01*
G01X774323Y572388D02*
X774320D01*
G01X776016Y573376D02*
X774324Y573714D01*
G01X774323Y572388D02*
X774320D01*
G01X791586Y568936D02*
X774323Y572388D01*
G01X779614Y572656D02*
X776016Y573376D01*
G01X791586Y568936D02*
X774323Y572388D01*
G01X785729Y571433D02*
X779614Y572656D01*
G01X791586Y568936D02*
X774323Y572388D01*
G01X791841Y570211D02*
X785729Y571433D01*
G01X791586Y568936D02*
X774323Y572388D01*
G01X774320D02*
X757966Y569209D01*
G01X774324Y573714D02*
X757966Y570534D01*
G01X774323Y572388D02*
X774320D01*
G01X774324Y573714D02*
X757966Y570534D01*
G01X776016Y573376D02*
X774324Y573714D01*
G01X791586Y568936D02*
X774323Y572388D01*
G01X776016Y573376D02*
X774324Y573714D01*
G01X779614Y572656D02*
X776016Y573376D01*
G01X785729Y571433D02*
X779614Y572656D01*
G01X791841Y570211D02*
X785729Y571433D01*
G01X835112Y559083D02*
X823813Y570382D01*
G01X836028Y560006D02*
X824460Y571574D01*
G01X836152Y559884D02*
X836028Y560006D01*
G01X835234Y558962D02*
X835112Y559083D01*
G01X836028Y560006D02*
X824460Y571574D01*
G01X836481Y555950D02*
G03X835234Y558962I-4259J1D01*
G01X837782Y555950D02*
G03X836152Y559884I-5560J1D01*
G01X836481Y553810D02*
Y555950D01*
G01X837781Y553810D02*
Y555950D01*
G01X837953Y550254D02*
G02X836481Y553810I3556J3555D01*
G01X838873Y551174D02*
G02X837781Y553810I2636J2636D01*
G01X840248Y547959D02*
X837953Y550254D01*
G01X841166Y548881D02*
X838873Y551174D01*
G01X836028Y560006D02*
X824460Y571574D01*
G01X835112Y559083D02*
X823813Y570382D01*
G01X835234Y558962D02*
X835112Y559083D01*
G01X836152Y559884D02*
X836028Y560006D01*
G01X835112Y559083D02*
X823813Y570382D01*
G01X837782Y555950D02*
G03X836152Y559884I-5560J1D01*
G01X836481Y555950D02*
G03X835234Y558962I-4259J1D01*
G01X837781Y553810D02*
Y555950D01*
G01X836481Y553810D02*
Y555950D01*
G01X838873Y551174D02*
G02X837781Y553810I2636J2636D01*
G01X837953Y550254D02*
G02X836481Y553810I3556J3555D01*
G01X841166Y548881D02*
X838873Y551174D01*
G01X840248Y547959D02*
X837953Y550254D01*
G01X796475Y562752D02*
X794903Y564322D01*
G01X795586Y561802D02*
X794265Y563121D01*
G01X797980Y559406D02*
G03X796475Y562752I-4472J0D01*
G01X796680Y559406D02*
G03X795586Y561802I-3171J0D01*
G01X797980Y557762D02*
Y559406D01*
G01X796680Y557763D02*
Y559406D01*
G01X798209Y557209D02*
G02X797980Y557762I553J553D01*
G01X797289Y556289D02*
G02X796680Y557763I1474J1472D01*
G01X799034Y556384D02*
X798209Y557209D01*
G01X798116Y555462D02*
X797289Y556289D01*
G01X795586Y561802D02*
X794265Y563121D01*
G01X796475Y562752D02*
X794903Y564322D01*
G01X796680Y559406D02*
G03X795586Y561802I-3171J0D01*
G01X797980Y559406D02*
G03X796475Y562752I-4472J0D01*
G01X796680Y557763D02*
Y559406D01*
G01X797980Y557762D02*
Y559406D01*
G01X797289Y556289D02*
G02X796680Y557763I1474J1472D01*
G01X798209Y557209D02*
G02X797980Y557762I553J553D01*
G01X798116Y555462D02*
X797289Y556289D01*
G01X799034Y556384D02*
X798209Y557209D01*
G01X810141Y565225D02*
X791586Y568936D01*
G01X814913Y563606D02*
X810649Y566450D01*
G01X813975Y562668D02*
X810141Y565225D01*
G01X816285Y561546D02*
X814913Y563606D01*
G01X814985Y561152D02*
X813975Y562668D01*
G01X816285Y556944D02*
Y561546D01*
G01X814985Y557483D02*
Y561152D01*
G01X812914Y553573D02*
X816285Y556944D01*
G01X811994Y554492D02*
X814985Y557483D01*
G01X812914Y551504D02*
G02Y553573I1035J1035D01*
G01X811994Y550584D02*
G02X811993Y554492I1955J1955D01*
G01X814034Y550384D02*
X812914Y551504D01*
G01X813116Y549462D02*
X811994Y550584D01*
G01X810141Y565225D02*
X791586Y568936D01*
G01X813975Y562668D02*
X810141Y565225D01*
G01X814913Y563606D02*
X810649Y566450D01*
G01X814985Y561152D02*
X813975Y562668D01*
G01X816285Y561546D02*
X814913Y563606D01*
G01X814985Y557483D02*
Y561152D01*
G01X816285Y556944D02*
Y561546D01*
G01X811994Y554492D02*
X814985Y557483D01*
G01X812914Y553573D02*
X816285Y556944D01*
G01X811994Y550584D02*
G02X811993Y554492I1955J1955D01*
G01X812914Y551504D02*
G02Y553573I1035J1035D01*
G01X813116Y549462D02*
X811994Y550584D01*
G01X814034Y550384D02*
X812914Y551504D01*
G01X809071Y573515D02*
X807457Y573858D01*
G01X813668Y572538D02*
X812054Y572881D01*
G01X818265Y571561D02*
X816651Y571904D01*
G01X823813Y570382D02*
X821248Y570927D01*
G01X809071Y573515D02*
X807457Y573858D01*
G01X813668Y572538D02*
X812054Y572881D01*
G01X818265Y571561D02*
X816651Y571904D01*
G01X823813Y570382D02*
X821248Y570927D01*
G01X810649Y566450D02*
X791841Y570211D01*
G01X810649Y566450D02*
X791841Y570211D01*
M02*
